G04 ================== begin FILE IDENTIFICATION RECORD ==================*
G04 Layout Name:  x887571-005_osp.brd*
G04 Film Name:    smb*
G04 File Format:  Gerber RS274X*
G04 File Origin:  Cadence Allegro 16.3-S036*
G04 Origin Date:  Thu Jul 03 00:06:57 2014*
G04 *
G04 Layer:  VIA CLASS/SOLDERMASK_BOTTOM*
G04 Layer:  PIN/SOLDERMASK_BOTTOM*
G04 Layer:  PACKAGE GEOMETRY/SOLDERMASK_BOTTOM*
G04 Layer:  DRAWING FORMAT/COMMON TEXT*
G04 Layer:  BOARD GEOMETRY/SOLDERMASK_BOTTOM*
G04 *
G04 Offset:    (0.0000 0.0000)*
G04 Mirror:    No*
G04 Mode:      Positive*
G04 Rotation:  0*
G04 FullContactRelief:  No*
G04 UndefLineWidth:     4.0000*
G04 ================== end FILE IDENTIFICATION RECORD ====================*
%FSLAX25Y25*MOIN*%
%IR0*IPPOS*OFA0.00000B0.00000*MIA0B0*SFA1.00000B1.00000*%
%ADD15R,.032X.197*%
%ADD12C,.032*%
%ADD24C,.061*%
%ADD18C,.07*%
%ADD29C,.044*%
%ADD11C,.026*%
%ADD30C,.027*%
%ADD25C,.081*%
%ADD14C,.054*%
%ADD28C,.083*%
%ADD17R,.032X.032*%
%ADD26C,.058*%
%ADD32C,.079*%
%ADD22R,.054X.054*%
%ADD27R,.079X.079*%
%ADD13C,.12*%
%ADD21C,.22*%
%ADD31C,.15*%
%ADD23C,.106*%
%ADD16R,.372X.248*%
%ADD19C,.145*%
%ADD20C,.176*%
%ADD10C,.276*%
%ADD33C,.01*%
%ADD34C,.012*%
%ADD35C,.013*%
%ADD36C,.015*%
%ADD37C,.004*%
%ADD38C,.005*%
%ADD39C,.006*%
%ADD40C,.007*%
%ADD41C,.008*%
G75*
%LPD*%
G75*
G36*
G01X-1655236Y-63259D02*
G02X-1631850I11693J12078D01*
G01Y-74803D01*
G02X-1655236I-11693J0D01*
G01Y-63259D01*
G37*
G36*
G01X-1454252Y-10472D02*
Y24961D01*
X-1667165D01*
Y-5354D01*
X-1620709D01*
Y-10472D01*
X-1454252D01*
G37*
G36*
G01X-1434764Y-134126D02*
G02X-1411378I11693J12078D01*
G01Y-145669D01*
G02X-1434764I-11693J0D01*
G01Y-134126D01*
G37*
G36*
G01X-1190669Y-80818D02*
G02X-1167283I11693J12078D01*
G01Y-92362D01*
G02X-1190669I-11693J0D01*
G01Y-80818D01*
G37*
G36*
G01X-572559Y-104441D02*
G02X-549173I11693J12078D01*
G01Y-115984D01*
G02X-572559I-11693J0D01*
G01Y-104441D01*
G37*
G36*
G01X-316654Y-80818D02*
G02X-293268I11693J12078D01*
G01Y-92362D01*
G02X-316654I-11693J0D01*
G01Y-80818D01*
G37*
G36*
G01X-44409Y-117826D02*
G02X-21024I11693J12078D01*
G01Y-129370D01*
G02X-44409I-11693J0D01*
G01Y-117826D01*
G37*
G54D10*
X-1645906Y-167953D03*
X-1522728Y-154950D03*
X-1047676Y-78740D03*
X-652638Y-154950D03*
X-177597Y-78740D03*
X6890Y-167953D03*
G54D20*
X-1356889Y-167165D03*
Y-118937D03*
X-1051613Y-167165D03*
Y-118937D03*
X-486810Y-167165D03*
Y-118937D03*
X-181534Y-167165D03*
Y-118937D03*
G54D11*
X-1656906Y-167953D03*
X-1645906Y-178953D03*
X-1653906Y-175453D03*
X-1653406Y-159953D03*
X-1645906Y-156953D03*
X-1634906Y-167953D03*
X-1637906Y-175453D03*
X-1638406Y-159953D03*
X-1530728Y-162450D03*
X-1533728Y-154950D03*
X-1530228Y-146950D03*
X-1522728Y-165950D03*
X-1514728Y-162450D03*
X-1515228Y-146950D03*
X-1522728Y-143950D03*
X-1511728Y-154950D03*
X-1058676Y-78740D03*
X-1047676Y-89740D03*
X-1055676Y-86240D03*
X-1055176Y-70740D03*
X-1047676Y-67740D03*
X-1039676Y-86240D03*
X-1040176Y-70740D03*
X-1036676Y-78740D03*
X-663638Y-154950D03*
X-652638Y-165950D03*
X-660638Y-162450D03*
X-660138Y-146950D03*
X-652638Y-143950D03*
X-641638Y-154950D03*
X-644638Y-162450D03*
X-645138Y-146950D03*
X-177597Y-89740D03*
X-185597Y-86240D03*
X-188597Y-78740D03*
X-185097Y-70740D03*
X-177597Y-67740D03*
X-169597Y-86240D03*
X-170097Y-70740D03*
X-166597Y-78740D03*
X-4110Y-167953D03*
X6890Y-178953D03*
X-1110Y-175453D03*
X14390Y-159953D03*
X-610D03*
X6890Y-156953D03*
X17890Y-167953D03*
X14890Y-175453D03*
G54D21*
X-1356889Y-145000D03*
X-1051613D03*
X-486810D03*
X-181534D03*
G54D30*
X-1015157Y-95824D03*
X-1012205Y-93068D03*
X-1009252Y-98580D03*
X-1015157Y-80864D03*
X-1012205Y-78108D03*
X-1009252Y-83620D03*
X-1015157Y-65903D03*
X-1012205Y-63147D03*
X-1009252Y-68659D03*
X-1015157Y-50942D03*
X-1012205Y-48187D03*
X-1009252Y-53698D03*
X-1006299Y-95824D03*
X-1000394Y-98580D03*
X-1003346Y-93068D03*
X-997441Y-95824D03*
X-994488Y-93068D03*
X-1000394Y-83620D03*
X-1006299Y-80864D03*
X-1003346Y-78108D03*
X-997441Y-80864D03*
X-994488Y-78108D03*
X-1006299Y-65903D03*
X-1003346Y-63147D03*
X-1000394Y-68659D03*
X-997441Y-65903D03*
X-994488Y-63147D03*
X-1006299Y-50942D03*
X-1003346Y-48187D03*
X-1000394Y-53698D03*
X-997441Y-50942D03*
X-994488Y-48187D03*
X-991535Y-98580D03*
Y-83620D03*
Y-68659D03*
Y-53698D03*
X-971850Y-95824D03*
X-968898Y-93068D03*
X-965945Y-98580D03*
X-962992Y-95824D03*
X-971850Y-80864D03*
X-965945Y-83620D03*
X-962992Y-80864D03*
X-968898Y-78108D03*
X-971850Y-65903D03*
X-965945Y-68659D03*
X-962992Y-65903D03*
X-968898Y-63147D03*
X-971850Y-50942D03*
X-965945Y-53698D03*
X-962992Y-50942D03*
X-968898Y-48187D03*
X-960039Y-93068D03*
X-957087Y-98580D03*
X-954134Y-95824D03*
X-951181Y-93068D03*
X-948228Y-98580D03*
X-960039Y-78108D03*
X-948228Y-83620D03*
X-957087D03*
X-954134Y-80864D03*
X-951181Y-78108D03*
X-960039Y-63147D03*
X-948228Y-68659D03*
X-957087D03*
X-954134Y-65903D03*
X-951181Y-63147D03*
X-960039Y-48187D03*
X-948228Y-53698D03*
X-957087D03*
X-954134Y-50942D03*
X-951181Y-48187D03*
X-145079Y-95824D03*
Y-80864D03*
Y-65903D03*
Y-50942D03*
X-142126Y-93068D03*
X-139173Y-98580D03*
X-136220Y-95824D03*
X-130315Y-98580D03*
X-133268Y-93068D03*
X-127362Y-95824D03*
X-142126Y-78108D03*
X-139173Y-83620D03*
X-130315D03*
X-136220Y-80864D03*
X-133268Y-78108D03*
X-127362Y-80864D03*
X-142126Y-63147D03*
X-139173Y-68659D03*
X-136220Y-65903D03*
X-133268Y-63147D03*
X-130315Y-68659D03*
X-127362Y-65903D03*
X-142126Y-48187D03*
X-139173Y-53698D03*
X-136220Y-50942D03*
X-133268Y-48187D03*
X-130315Y-53698D03*
X-127362Y-50942D03*
X-121457Y-98580D03*
X-124409Y-93068D03*
X-121457Y-83620D03*
X-124409Y-78108D03*
X-121457Y-68659D03*
X-124409Y-63147D03*
X-121457Y-53698D03*
X-124409Y-48187D03*
X-101772Y-95824D03*
X-98819Y-93068D03*
X-95866Y-98580D03*
X-101772Y-80864D03*
X-95866Y-83620D03*
X-98819Y-78108D03*
X-101772Y-65903D03*
X-95866Y-68659D03*
X-98819Y-63147D03*
X-101772Y-50942D03*
X-95866Y-53698D03*
X-98819Y-48187D03*
X-92913Y-95824D03*
X-89961Y-93068D03*
X-87008Y-98580D03*
X-84055Y-95824D03*
X-81102Y-93068D03*
X-92913Y-80864D03*
X-89961Y-78108D03*
X-87008Y-83620D03*
X-84055Y-80864D03*
X-81102Y-78108D03*
X-92913Y-65903D03*
X-89961Y-63147D03*
X-87008Y-68659D03*
X-84055Y-65903D03*
X-81102Y-63147D03*
X-92913Y-50942D03*
X-89961Y-48187D03*
X-87008Y-53698D03*
X-84055Y-50942D03*
X-81102Y-48187D03*
X-78150Y-98580D03*
Y-83620D03*
Y-68659D03*
Y-53698D03*
G54D12*
X-1656000Y-135000D03*
X-1615984Y-173071D03*
Y-178583D03*
Y-167559D03*
X-1608110Y-172677D03*
Y-178189D03*
Y-167165D03*
X-1615984Y-162047D03*
Y-151024D03*
Y-156535D03*
X-1608110Y-161654D03*
Y-150630D03*
Y-156142D03*
X-1615984Y-134488D03*
Y-140000D03*
Y-145512D03*
X-1608110Y-134094D03*
Y-139606D03*
Y-145118D03*
X-1615984Y-128976D03*
Y-123465D03*
Y-117953D03*
X-1608110Y-128583D03*
Y-123071D03*
Y-117559D03*
X-1615984Y-112441D03*
Y-106929D03*
Y-101417D03*
X-1608110Y-112047D03*
Y-106535D03*
Y-101024D03*
X-1615984Y-95906D03*
X-1600236Y-167559D03*
X-1592362Y-167165D03*
X-1600236Y-173071D03*
X-1592362Y-172677D03*
X-1600236Y-178583D03*
X-1592362Y-178189D03*
X-1600236Y-151024D03*
X-1592362Y-150630D03*
X-1600236Y-156535D03*
X-1592362Y-156142D03*
X-1600236Y-162047D03*
X-1592362Y-161654D03*
X-1600236Y-134488D03*
X-1592362Y-134094D03*
X-1600236Y-140000D03*
X-1592362Y-139606D03*
X-1600236Y-145512D03*
X-1592362Y-145118D03*
X-1600236Y-128976D03*
Y-117953D03*
Y-123465D03*
X-1592362Y-128583D03*
Y-117559D03*
Y-123071D03*
X-1600236Y-101417D03*
Y-106929D03*
Y-112441D03*
X-1592362Y-101024D03*
Y-106535D03*
Y-112047D03*
X-1600236Y-95906D03*
X-1584488Y-167559D03*
X-1576614Y-167165D03*
X-1584488Y-173071D03*
X-1576614Y-172677D03*
X-1584488Y-178583D03*
X-1576614Y-178189D03*
X-1584488Y-151024D03*
X-1576614Y-150630D03*
X-1584488Y-156535D03*
X-1576614Y-156142D03*
X-1584488Y-162047D03*
X-1576614Y-161654D03*
X-1584488Y-134488D03*
X-1576614Y-134094D03*
X-1584488Y-140000D03*
X-1576614Y-139606D03*
X-1584488Y-145512D03*
X-1576614Y-145118D03*
X-1584488Y-128976D03*
X-1576614Y-128583D03*
X-1584488Y-117953D03*
X-1576614Y-117559D03*
X-1584488Y-123465D03*
X-1576614Y-123071D03*
X-1584488Y-101417D03*
X-1576614Y-101024D03*
X-1584488Y-106929D03*
X-1576614Y-106535D03*
X-1584488Y-112441D03*
X-1576614Y-112047D03*
X-1584488Y-95906D03*
X-1568740Y-167559D03*
X-1560866Y-167165D03*
X-1568740Y-173071D03*
X-1560866Y-172677D03*
X-1568740Y-178583D03*
X-1560866Y-178189D03*
X-1568740Y-151024D03*
X-1560866Y-150630D03*
X-1568740Y-156535D03*
X-1560866Y-156142D03*
X-1568740Y-162047D03*
X-1560866Y-161654D03*
X-1568740Y-134488D03*
X-1560866Y-134094D03*
X-1568740Y-140000D03*
X-1560866Y-139606D03*
X-1568740Y-145512D03*
X-1560866Y-145118D03*
X-1568740Y-128976D03*
Y-117953D03*
Y-123465D03*
X-1560866Y-128583D03*
Y-117559D03*
Y-123071D03*
X-1568740Y-101417D03*
Y-106929D03*
Y-112441D03*
X-1560866Y-101024D03*
Y-106535D03*
Y-112047D03*
X-1568740Y-95906D03*
X-1552992Y-167559D03*
X-1545118Y-167165D03*
X-1552992Y-173071D03*
X-1545118Y-172677D03*
X-1552992Y-178583D03*
Y-151024D03*
X-1545118Y-150630D03*
X-1552992Y-156535D03*
X-1545118Y-156142D03*
X-1552992Y-162047D03*
X-1545118Y-161654D03*
X-1552992Y-134488D03*
X-1545118Y-134094D03*
X-1552992Y-140000D03*
X-1545118Y-139606D03*
X-1552992Y-145512D03*
X-1545118Y-145118D03*
X-1552992Y-128976D03*
Y-117953D03*
Y-123465D03*
X-1545118Y-128583D03*
Y-117559D03*
Y-123071D03*
X-1552992Y-101417D03*
Y-106929D03*
Y-112441D03*
X-1545118Y-101024D03*
Y-106535D03*
Y-112047D03*
X-1552992Y-95906D03*
X-1535063Y-22160D03*
X-1535000Y-32500D03*
X-1524359Y-125359D03*
X-1497043Y-169390D03*
X-1486693Y-76890D03*
X-1475063Y-22160D03*
X-1450000Y-112500D03*
X-1437500Y-175000D03*
X-1421250Y-81250D03*
X-1387500Y-150000D03*
X-1371250Y-112500D03*
X-1368750Y-82500D03*
X-1324840Y-82120D03*
X-1335400Y-75000D03*
X-1324500Y-26959D03*
X-1311200Y-30200D03*
X-1298780Y-52200D03*
X-1298000Y-41200D03*
X-1298700Y-35700D03*
X-1255315Y-157350D03*
X-1232500Y-45000D03*
X-1217520Y-157350D03*
X-1197008Y-167953D03*
X-1189134Y-167559D03*
X-1197008Y-173465D03*
X-1189134Y-173071D03*
X-1197008Y-178976D03*
X-1189134Y-178583D03*
X-1197008Y-151417D03*
X-1189134Y-151024D03*
X-1197008Y-156929D03*
X-1189134Y-156535D03*
X-1197008Y-162441D03*
X-1189134Y-162047D03*
X-1197008Y-134882D03*
X-1189134Y-134488D03*
X-1197008Y-140394D03*
X-1189134Y-140000D03*
X-1197008Y-145906D03*
X-1189134Y-145512D03*
X-1197008Y-129370D03*
X-1191000Y-46500D03*
X-1181260Y-167953D03*
X-1173386Y-167559D03*
X-1181260Y-173465D03*
X-1173386Y-173071D03*
X-1181260Y-178976D03*
X-1173386Y-178583D03*
X-1181260Y-151417D03*
X-1173386Y-151024D03*
X-1181260Y-156929D03*
X-1173386Y-156535D03*
X-1181260Y-162441D03*
X-1173386Y-162047D03*
X-1181260Y-134882D03*
X-1173386Y-134488D03*
X-1181260Y-140394D03*
X-1173386Y-140000D03*
X-1181260Y-145906D03*
X-1173386Y-145512D03*
X-1181260Y-129370D03*
X-1178950Y-23250D03*
X-1165512Y-167953D03*
X-1157638Y-167559D03*
X-1165512Y-173465D03*
X-1157638Y-173071D03*
X-1165512Y-178976D03*
X-1157638Y-178583D03*
X-1165512Y-151417D03*
X-1157638Y-151024D03*
X-1165512Y-156929D03*
X-1157638Y-156535D03*
X-1165512Y-162441D03*
X-1157638Y-162047D03*
X-1165512Y-134882D03*
X-1157638Y-134488D03*
X-1165512Y-140394D03*
X-1157638Y-140000D03*
X-1165512Y-145906D03*
X-1157638Y-145512D03*
X-1165512Y-129370D03*
X-1160150Y-26750D03*
X-1158700Y-16250D03*
X-1151500Y-15000D03*
X-1159700Y-5750D03*
X-1124700Y-180000D03*
X-1124900Y-170650D03*
X-1121870Y-104330D03*
X-1128810Y-104171D03*
X-1115490Y-104240D03*
X-1095600Y-179600D03*
X-1096278Y-170650D03*
X-1100000Y-15000D03*
X-1056900Y-56300D03*
X-1051200Y-44100D03*
X-1054900Y-29800D03*
X-1047289Y-26300D03*
X-1054600Y-5100D03*
X-1047300Y-2700D03*
X-1014488Y-167953D03*
Y-173465D03*
Y-178976D03*
Y-151417D03*
Y-156929D03*
Y-162441D03*
Y-134882D03*
Y-140394D03*
Y-145906D03*
Y-129370D03*
X-1012500Y-7500D03*
X-1006614Y-167559D03*
X-998740Y-167953D03*
X-1006614Y-173071D03*
X-998740Y-173465D03*
X-1006614Y-178583D03*
X-998740Y-178976D03*
X-1006614Y-151024D03*
X-998740Y-151417D03*
X-1006614Y-156535D03*
X-998740Y-156929D03*
X-1006614Y-162047D03*
X-998740Y-162441D03*
X-1006614Y-134488D03*
X-998740Y-134882D03*
X-1006614Y-140000D03*
X-998740Y-140394D03*
X-1006614Y-145512D03*
X-998740Y-145906D03*
Y-129370D03*
X-990866Y-167559D03*
X-982992Y-167953D03*
X-990866Y-173071D03*
X-982992Y-173465D03*
X-990866Y-178583D03*
X-982992Y-178976D03*
X-990866Y-151024D03*
X-982992Y-151417D03*
X-990866Y-156535D03*
X-982992Y-156929D03*
X-990866Y-162047D03*
X-982992Y-162441D03*
X-990866Y-134488D03*
X-982992Y-134882D03*
X-990866Y-140000D03*
X-982992Y-140394D03*
X-990866Y-145512D03*
X-982992Y-145906D03*
Y-129370D03*
X-975118Y-167559D03*
Y-173071D03*
Y-178583D03*
Y-151024D03*
Y-156535D03*
Y-162047D03*
Y-134488D03*
Y-140000D03*
Y-145512D03*
X-970000Y-7500D03*
X-932500D03*
X-860000Y-45000D03*
X-745906Y-173071D03*
Y-178583D03*
Y-167559D03*
Y-162047D03*
Y-151024D03*
Y-156535D03*
Y-134488D03*
Y-140000D03*
Y-145512D03*
Y-128976D03*
Y-123465D03*
Y-117953D03*
Y-112441D03*
Y-106929D03*
Y-101417D03*
Y-95906D03*
X-738032Y-172677D03*
Y-178189D03*
Y-167165D03*
X-730157Y-167559D03*
Y-173071D03*
Y-178583D03*
X-738032Y-161654D03*
Y-150630D03*
Y-156142D03*
X-730157Y-151024D03*
Y-156535D03*
Y-162047D03*
X-738032Y-134094D03*
Y-139606D03*
Y-145118D03*
X-730157Y-134488D03*
Y-140000D03*
Y-145512D03*
Y-128976D03*
X-738032Y-128583D03*
X-730157Y-117953D03*
Y-123465D03*
X-738032Y-123071D03*
Y-117559D03*
X-730157Y-101417D03*
Y-106929D03*
Y-112441D03*
X-738032Y-112047D03*
Y-106535D03*
Y-101024D03*
X-730157Y-95906D03*
X-722283Y-167165D03*
X-714409Y-167559D03*
X-722283Y-172677D03*
X-714409Y-173071D03*
X-722283Y-178189D03*
X-714409Y-178583D03*
X-722283Y-150630D03*
X-714409Y-151024D03*
X-722283Y-156142D03*
X-714409Y-156535D03*
X-722283Y-161654D03*
X-714409Y-162047D03*
X-722283Y-134094D03*
X-714409Y-134488D03*
X-722283Y-139606D03*
X-714409Y-140000D03*
X-722283Y-145118D03*
X-714409Y-145512D03*
X-722283Y-128583D03*
Y-117559D03*
Y-123071D03*
X-714409Y-128976D03*
Y-117953D03*
Y-123465D03*
X-722283Y-101024D03*
Y-106535D03*
Y-112047D03*
X-714409Y-101417D03*
Y-106929D03*
Y-112441D03*
Y-95906D03*
X-706535Y-167165D03*
X-698661Y-167559D03*
X-706535Y-172677D03*
X-698661Y-173071D03*
X-706535Y-178189D03*
X-698661Y-178583D03*
X-706535Y-150630D03*
X-698661Y-151024D03*
X-706535Y-156142D03*
X-698661Y-156535D03*
X-706535Y-161654D03*
X-698661Y-162047D03*
X-706535Y-134094D03*
X-698661Y-134488D03*
X-706535Y-139606D03*
X-698661Y-140000D03*
X-706535Y-145118D03*
X-698661Y-145512D03*
X-706535Y-128583D03*
Y-117559D03*
Y-123071D03*
X-698661Y-128976D03*
Y-117953D03*
Y-123465D03*
X-706535Y-101024D03*
Y-106535D03*
Y-112047D03*
X-698661Y-101417D03*
Y-106929D03*
Y-112441D03*
Y-95906D03*
X-690787Y-167165D03*
X-682913Y-167559D03*
X-690787Y-172677D03*
X-682913Y-173071D03*
X-690787Y-178189D03*
X-682913Y-178583D03*
X-690787Y-150630D03*
X-682913Y-151024D03*
X-690787Y-156142D03*
X-682913Y-156535D03*
X-690787Y-161654D03*
X-682913Y-162047D03*
X-690787Y-134094D03*
X-682913Y-134488D03*
X-690787Y-139606D03*
X-682913Y-140000D03*
X-690787Y-145118D03*
X-682913Y-145512D03*
X-690787Y-128583D03*
X-682913Y-128976D03*
X-690787Y-117559D03*
X-682913Y-117953D03*
X-690787Y-123071D03*
X-682913Y-123465D03*
X-690787Y-101024D03*
X-682913Y-101417D03*
X-690787Y-106535D03*
X-682913Y-106929D03*
X-690787Y-112047D03*
X-682913Y-112441D03*
Y-95906D03*
X-685000Y-45000D03*
X-675039Y-167165D03*
Y-172677D03*
Y-150630D03*
Y-156142D03*
Y-161654D03*
Y-134094D03*
Y-139606D03*
Y-145118D03*
Y-128583D03*
Y-117559D03*
Y-123071D03*
Y-101024D03*
Y-106535D03*
Y-112047D03*
X-626964Y-169390D03*
X-621614Y-76890D03*
X-577500Y-115000D03*
X-502500Y-12500D03*
X-444440Y-80710D03*
X-442800Y-46600D03*
X-430180Y-52100D03*
X-429400Y-41100D03*
X-430400Y-35600D03*
X-424500Y-26500D03*
X-385237Y-157350D03*
X-386500Y-56500D03*
Y-5500D03*
X-374000Y-31500D03*
X-347441Y-157350D03*
X-348000Y-31500D03*
X-342400Y-87500D03*
X-326929Y-167953D03*
X-319055Y-167559D03*
X-326929Y-173465D03*
X-319055Y-173071D03*
X-326929Y-178976D03*
X-319055Y-178583D03*
X-326929Y-151417D03*
X-319055Y-151024D03*
X-326929Y-156929D03*
X-319055Y-156535D03*
X-326929Y-162441D03*
X-319055Y-162047D03*
X-326929Y-134882D03*
X-319055Y-134488D03*
X-326929Y-140394D03*
X-319055Y-140000D03*
X-326929Y-145906D03*
X-319055Y-145512D03*
X-326929Y-129370D03*
X-321500Y-47500D03*
X-311181Y-167953D03*
X-303307Y-167559D03*
X-311181Y-173465D03*
X-303307Y-173071D03*
X-311181Y-178976D03*
X-303307Y-178583D03*
X-311181Y-151417D03*
X-303307Y-151024D03*
X-311181Y-156929D03*
X-303307Y-156535D03*
X-311181Y-162441D03*
X-303307Y-162047D03*
X-311181Y-134882D03*
X-303307Y-134488D03*
X-311181Y-140394D03*
X-303307Y-140000D03*
X-311181Y-145906D03*
X-303307Y-145512D03*
X-311181Y-129370D03*
X-302500Y-15200D03*
X-295433Y-167953D03*
X-287559Y-167559D03*
X-295433Y-173465D03*
X-287559Y-173071D03*
X-295433Y-178976D03*
X-287559Y-178583D03*
X-295433Y-151417D03*
X-287559Y-151024D03*
X-295433Y-156929D03*
X-287559Y-156535D03*
X-295433Y-162441D03*
X-287559Y-162047D03*
X-295433Y-134882D03*
X-287559Y-134488D03*
X-295433Y-140394D03*
X-287559Y-140000D03*
X-295433Y-145906D03*
X-287559Y-145512D03*
X-295433Y-129370D03*
X-289500Y-32500D03*
X-290800Y-26000D03*
X-254800Y-180000D03*
X-258732Y-104171D03*
X-255500Y-25500D03*
X-268000Y-500D03*
X-245411Y-104240D03*
X-251792Y-104330D03*
X-225400Y-179800D03*
X-226200Y-170650D03*
X-232874Y-104200D03*
X-230500Y-500D03*
X-191000Y-56400D03*
X-190300Y-28900D03*
Y-4200D03*
X-179800Y-43500D03*
X-176350Y-27200D03*
X-175100Y-1800D03*
X-144409Y-167953D03*
Y-173465D03*
Y-178976D03*
Y-151417D03*
Y-156929D03*
Y-162441D03*
Y-134882D03*
Y-140394D03*
Y-145906D03*
Y-129370D03*
X-136535Y-167559D03*
X-128661Y-167953D03*
X-136535Y-173071D03*
X-128661Y-173465D03*
X-136535Y-178583D03*
X-128661Y-178976D03*
X-136535Y-151024D03*
X-128661Y-151417D03*
X-136535Y-156535D03*
X-128661Y-156929D03*
X-136535Y-162047D03*
X-128661Y-162441D03*
X-136535Y-134488D03*
X-128661Y-134882D03*
X-136535Y-140000D03*
X-128661Y-140394D03*
X-136535Y-145512D03*
X-128661Y-145906D03*
Y-129370D03*
X-120787Y-167559D03*
X-112913Y-167953D03*
X-120787Y-173071D03*
X-112913Y-173465D03*
X-120787Y-178583D03*
X-112913Y-178976D03*
X-120787Y-151024D03*
X-112913Y-151417D03*
X-120787Y-156535D03*
X-112913Y-156929D03*
X-120787Y-162047D03*
X-112913Y-162441D03*
X-120787Y-134488D03*
X-112913Y-134882D03*
X-120787Y-140000D03*
X-112913Y-140394D03*
X-120787Y-145512D03*
X-112913Y-145906D03*
Y-129370D03*
X-126500Y-8500D03*
X-105039Y-167559D03*
Y-173071D03*
Y-178583D03*
Y-151024D03*
Y-156535D03*
Y-162047D03*
Y-134488D03*
Y-140000D03*
Y-145512D03*
X-59500Y-108500D03*
Y-58500D03*
Y-21000D03*
X-34500Y-83500D03*
X-9500Y-58500D03*
X3000Y-96000D03*
G54D40*
G01X-1189333Y-572500D02*
Y-565500D01*
X-1187667D01*
X-1187000Y-565850D01*
X-1186500Y-566317D01*
X-1186083Y-567017D01*
X-1185750Y-567833D01*
X-1185667Y-569000D01*
X-1185750Y-570167D01*
X-1186083Y-570983D01*
X-1186500Y-571684D01*
X-1187000Y-572150D01*
X-1187667Y-572500D01*
X-1189333D01*
G01X-1180700D02*
X-1181367Y-572383D01*
X-1181950Y-571917D01*
X-1182450Y-571217D01*
X-1182783Y-570400D01*
X-1182950Y-569467D01*
Y-568533D01*
X-1182783Y-567600D01*
X-1182450Y-566783D01*
X-1181950Y-566083D01*
X-1181367Y-565617D01*
X-1180700Y-565500D01*
X-1180033Y-565617D01*
X-1179450Y-566083D01*
X-1178950Y-566783D01*
X-1178617Y-567600D01*
X-1178450Y-568533D01*
Y-569467D01*
X-1178617Y-570400D01*
X-1178950Y-571217D01*
X-1179450Y-571917D01*
X-1180033Y-572383D01*
X-1180700Y-572500D01*
G01X-1172067Y-566083D02*
X-1172567Y-565733D01*
X-1173150Y-565500D01*
X-1173817D01*
X-1174567Y-565850D01*
X-1175150Y-566433D01*
X-1175567Y-567133D01*
X-1175900Y-568300D01*
X-1175983Y-569350D01*
X-1175817Y-570400D01*
X-1175567Y-571100D01*
X-1175067Y-571800D01*
X-1174483Y-572267D01*
X-1173900Y-572500D01*
X-1173317D01*
X-1172733Y-572267D01*
X-1172233Y-571917D01*
X-1171817Y-571450D01*
G01X-1168933Y-565500D02*
Y-570517D01*
X-1168600Y-571567D01*
X-1167933Y-572267D01*
X-1167100Y-572500D01*
X-1166267Y-572267D01*
X-1165600Y-571567D01*
X-1165267Y-570517D01*
Y-565500D01*
G01X-1162467Y-572500D02*
Y-565500D01*
X-1160300Y-571333D01*
X-1158133Y-565500D01*
Y-572500D01*
G01X-1151833D02*
X-1155167D01*
Y-565500D01*
X-1151833D01*
G01X-1153167Y-568883D02*
X-1155167D01*
G01X-1148617Y-572500D02*
Y-565500D01*
X-1144783Y-572500D01*
Y-565500D01*
G01X-1139900D02*
Y-572500D01*
G01X-1141817Y-565500D02*
X-1137983D01*
G01X-1128217Y-572500D02*
Y-565500D01*
X-1124383Y-572500D01*
Y-565500D01*
G01X-1121333D02*
Y-570517D01*
X-1121000Y-571567D01*
X-1120333Y-572267D01*
X-1119500Y-572500D01*
X-1118667Y-572267D01*
X-1118000Y-571567D01*
X-1117667Y-570517D01*
Y-565500D01*
G01X-1114867Y-572500D02*
Y-565500D01*
X-1112700Y-571333D01*
X-1110533Y-565500D01*
Y-572500D01*
G01X-1105233Y-568767D02*
X-1104900Y-568417D01*
X-1104650Y-567833D01*
X-1104483Y-567017D01*
X-1104650Y-566317D01*
X-1104983Y-565850D01*
X-1105567Y-565500D01*
X-1107817D01*
Y-572500D01*
X-1105067D01*
X-1104483Y-572033D01*
X-1104150Y-571333D01*
X-1103983Y-570517D01*
X-1104150Y-569700D01*
X-1104650Y-569000D01*
X-1105233Y-568767D01*
X-1107817D01*
G01X-1097433Y-572500D02*
X-1100767D01*
Y-565500D01*
X-1097433D01*
G01X-1098767Y-568883D02*
X-1100767D01*
G01X-1093967Y-572500D02*
Y-565500D01*
X-1091883D01*
X-1091217Y-565850D01*
X-1090800Y-566317D01*
X-1090633Y-567250D01*
X-1090800Y-568183D01*
X-1091300Y-568767D01*
X-1091883Y-569117D01*
X-1093967D01*
G01X-1091883D02*
X-1090633Y-572500D01*
G01X-1189250Y-531567D02*
X-1188583Y-532150D01*
X-1187833Y-532500D01*
X-1187167D01*
X-1186500Y-532150D01*
X-1186000Y-531567D01*
X-1185750Y-530750D01*
X-1185917Y-529933D01*
X-1186333Y-529233D01*
X-1187083Y-528767D01*
X-1188083Y-528533D01*
X-1188667Y-528067D01*
X-1188917Y-527250D01*
X-1188750Y-526433D01*
X-1188333Y-525850D01*
X-1187750Y-525500D01*
X-1187167D01*
X-1186583Y-525733D01*
X-1186083Y-526317D01*
G01X-1182450Y-532500D02*
Y-525500D01*
G01X-1178950D02*
Y-532500D01*
G01Y-529000D02*
X-1182450D01*
G01X-1172233Y-532500D02*
X-1175567D01*
Y-525500D01*
X-1172233D01*
G01X-1173567Y-528883D02*
X-1175567D01*
G01X-1165433Y-532500D02*
X-1168767D01*
Y-525500D01*
X-1165433D01*
G01X-1166767Y-528883D02*
X-1168767D01*
G01X-1160300Y-525500D02*
Y-532500D01*
G01X-1162217Y-525500D02*
X-1158383D01*
G01X-1146700D02*
Y-532500D01*
G01X-1148617Y-525500D02*
X-1144783D01*
G01X-1140900D02*
X-1138900D01*
G01X-1139900D02*
Y-532500D01*
G01X-1140900D02*
X-1138900D01*
G01X-1133100Y-525500D02*
Y-532500D01*
G01X-1135017Y-525500D02*
X-1131183D01*
G01X-1127967D02*
Y-532500D01*
X-1124633D01*
G01X-1117833D02*
X-1121167D01*
Y-525500D01*
X-1117833D01*
G01X-1119167Y-528883D02*
X-1121167D01*
G01X-1112700Y-532733D02*
X-1112867Y-532617D01*
Y-532383D01*
X-1112700Y-532267D01*
X-1112533Y-532383D01*
Y-532617D01*
X-1112700Y-532733D01*
G01Y-529584D02*
X-1112867Y-529467D01*
Y-529233D01*
X-1112700Y-529117D01*
X-1112533Y-529233D01*
Y-529467D01*
X-1112700Y-529584D01*
G01X-1187500Y-485500D02*
Y-492500D01*
G01X-1189417Y-485500D02*
X-1185583D01*
G01X-1181700D02*
X-1179700D01*
G01X-1180700D02*
Y-492500D01*
G01X-1181700D02*
X-1179700D01*
G01X-1173900Y-485500D02*
Y-492500D01*
G01X-1175817Y-485500D02*
X-1171983D01*
G01X-1168767D02*
Y-492500D01*
X-1165433D01*
G01X-1158633D02*
X-1161967D01*
Y-485500D01*
X-1158633D01*
G01X-1159967Y-488883D02*
X-1161967D01*
G01X-916667Y-570000D02*
Y-563000D01*
X-914583D01*
X-913917Y-563350D01*
X-913500Y-563817D01*
X-913333Y-564750D01*
X-913500Y-565683D01*
X-914000Y-566267D01*
X-914583Y-566617D01*
X-916667D01*
G01X-914583D02*
X-913333Y-570000D01*
G01X-906533D02*
X-909867D01*
Y-563000D01*
X-906533D01*
G01X-907867Y-566383D02*
X-909867D01*
G01X-903483Y-563000D02*
X-901400Y-570000D01*
X-899317Y-563000D01*
G01X-907850Y-451567D02*
X-907183Y-452150D01*
X-906433Y-452500D01*
X-905767D01*
X-905100Y-452150D01*
X-904600Y-451567D01*
X-904350Y-450750D01*
X-904517Y-449933D01*
X-904933Y-449233D01*
X-905683Y-448767D01*
X-906683Y-448533D01*
X-907267Y-448067D01*
X-907517Y-447250D01*
X-907350Y-446433D01*
X-906933Y-445850D01*
X-906350Y-445500D01*
X-905767D01*
X-905183Y-445733D01*
X-904683Y-446317D01*
G01X-897467Y-446083D02*
X-897967Y-445733D01*
X-898550Y-445500D01*
X-899217D01*
X-899967Y-445850D01*
X-900550Y-446433D01*
X-900967Y-447133D01*
X-901300Y-448300D01*
X-901383Y-449350D01*
X-901217Y-450400D01*
X-900967Y-451100D01*
X-900467Y-451800D01*
X-899883Y-452267D01*
X-899300Y-452500D01*
X-898717D01*
X-898133Y-452267D01*
X-897633Y-451917D01*
X-897217Y-451450D01*
G01X-894583Y-452500D02*
X-892500Y-445500D01*
X-890417Y-452500D01*
G01X-891167Y-450050D02*
X-893833D01*
G01X-887367Y-445500D02*
Y-452500D01*
X-884033D01*
G01X-877233D02*
X-880567D01*
Y-445500D01*
X-877233D01*
G01X-878567Y-448883D02*
X-880567D01*
G01X-874333Y-572500D02*
Y-565500D01*
X-872667D01*
X-872000Y-565850D01*
X-871500Y-566317D01*
X-871083Y-567017D01*
X-870750Y-567833D01*
X-870667Y-569000D01*
X-870750Y-570167D01*
X-871083Y-570983D01*
X-871500Y-571684D01*
X-872000Y-572150D01*
X-872667Y-572500D01*
X-874333D01*
G01X-866700Y-565500D02*
X-864700D01*
G01X-865700D02*
Y-572500D01*
G01X-866700D02*
X-864700D01*
G01X-860650Y-571567D02*
X-859983Y-572150D01*
X-859233Y-572500D01*
X-858567D01*
X-857900Y-572150D01*
X-857400Y-571567D01*
X-857150Y-570750D01*
X-857317Y-569933D01*
X-857733Y-569233D01*
X-858483Y-568767D01*
X-859483Y-568533D01*
X-860067Y-568067D01*
X-860317Y-567250D01*
X-860150Y-566433D01*
X-859733Y-565850D01*
X-859150Y-565500D01*
X-858567D01*
X-857983Y-565733D01*
X-857483Y-566317D01*
G01X-850267Y-566083D02*
X-850767Y-565733D01*
X-851350Y-565500D01*
X-852017D01*
X-852767Y-565850D01*
X-853350Y-566433D01*
X-853767Y-567133D01*
X-854100Y-568300D01*
X-854183Y-569350D01*
X-854017Y-570400D01*
X-853767Y-571100D01*
X-853267Y-571800D01*
X-852683Y-572267D01*
X-852100Y-572500D01*
X-851517D01*
X-850933Y-572267D01*
X-850433Y-571917D01*
X-850017Y-571450D01*
G01X-846967Y-565500D02*
Y-572500D01*
X-843633D01*
G01X-838500D02*
X-839167Y-572383D01*
X-839750Y-571917D01*
X-840250Y-571217D01*
X-840583Y-570400D01*
X-840750Y-569467D01*
Y-568533D01*
X-840583Y-567600D01*
X-840250Y-566783D01*
X-839750Y-566083D01*
X-839167Y-565617D01*
X-838500Y-565500D01*
X-837833Y-565617D01*
X-837250Y-566083D01*
X-836750Y-566783D01*
X-836417Y-567600D01*
X-836250Y-568533D01*
Y-569467D01*
X-836417Y-570400D01*
X-836750Y-571217D01*
X-837250Y-571917D01*
X-837833Y-572383D01*
X-838500Y-572500D01*
G01X-833450Y-571567D02*
X-832783Y-572150D01*
X-832033Y-572500D01*
X-831367D01*
X-830700Y-572150D01*
X-830200Y-571567D01*
X-829950Y-570750D01*
X-830117Y-569933D01*
X-830533Y-569233D01*
X-831283Y-568767D01*
X-832283Y-568533D01*
X-832867Y-568067D01*
X-833117Y-567250D01*
X-832950Y-566433D01*
X-832533Y-565850D01*
X-831950Y-565500D01*
X-831367D01*
X-830783Y-565733D01*
X-830283Y-566317D01*
G01X-823233Y-572500D02*
X-826567D01*
Y-565500D01*
X-823233D01*
G01X-824567Y-568883D02*
X-826567D01*
G01X-819933Y-572500D02*
Y-565500D01*
X-818267D01*
X-817600Y-565850D01*
X-817100Y-566317D01*
X-816683Y-567017D01*
X-816350Y-567833D01*
X-816267Y-569000D01*
X-816350Y-570167D01*
X-816683Y-570983D01*
X-817100Y-571684D01*
X-817600Y-572150D01*
X-818267Y-572500D01*
X-819933D01*
G01X-807000Y-565500D02*
X-805833Y-572500D01*
X-804500Y-565500D01*
X-803167Y-572500D01*
X-802000Y-565500D01*
G01X-798700D02*
X-796700D01*
G01X-797700D02*
Y-572500D01*
G01X-798700D02*
X-796700D01*
G01X-790900Y-565500D02*
Y-572500D01*
G01X-792817Y-565500D02*
X-788983D01*
G01X-785850Y-572500D02*
Y-565500D01*
G01X-782350D02*
Y-572500D01*
G01Y-569000D02*
X-785850D01*
G01X-777300Y-572500D02*
X-777967Y-572383D01*
X-778550Y-571917D01*
X-779050Y-571217D01*
X-779383Y-570400D01*
X-779550Y-569467D01*
Y-568533D01*
X-779383Y-567600D01*
X-779050Y-566783D01*
X-778550Y-566083D01*
X-777967Y-565617D01*
X-777300Y-565500D01*
X-776633Y-565617D01*
X-776050Y-566083D01*
X-775550Y-566783D01*
X-775217Y-567600D01*
X-775050Y-568533D01*
Y-569467D01*
X-775217Y-570400D01*
X-775550Y-571217D01*
X-776050Y-571917D01*
X-776633Y-572383D01*
X-777300Y-572500D01*
G01X-772333Y-565500D02*
Y-570517D01*
X-772000Y-571567D01*
X-771333Y-572267D01*
X-770500Y-572500D01*
X-769667Y-572267D01*
X-769000Y-571567D01*
X-768667Y-570517D01*
Y-565500D01*
G01X-763700D02*
Y-572500D01*
G01X-765617Y-565500D02*
X-761783D01*
G01X-750100D02*
Y-572500D01*
G01X-752017Y-565500D02*
X-748183D01*
G01X-745050Y-572500D02*
Y-565500D01*
G01X-741550D02*
Y-572500D01*
G01Y-569000D02*
X-745050D01*
G01X-734833Y-572500D02*
X-738167D01*
Y-565500D01*
X-734833D01*
G01X-736167Y-568883D02*
X-738167D01*
G01X-724567Y-572500D02*
Y-565500D01*
X-722567D01*
X-721900Y-565850D01*
X-721400Y-566667D01*
X-721233Y-567600D01*
X-721400Y-568533D01*
X-721817Y-569233D01*
X-722567Y-569584D01*
X-724567D01*
G01X-717767Y-572500D02*
Y-565500D01*
X-715683D01*
X-715017Y-565850D01*
X-714600Y-566317D01*
X-714433Y-567250D01*
X-714600Y-568183D01*
X-715100Y-568767D01*
X-715683Y-569117D01*
X-717767D01*
G01X-715683D02*
X-714433Y-572500D01*
G01X-710300Y-565500D02*
X-708300D01*
G01X-709300D02*
Y-572500D01*
G01X-710300D02*
X-708300D01*
G01X-702500D02*
X-703167Y-572383D01*
X-703750Y-571917D01*
X-704250Y-571217D01*
X-704583Y-570400D01*
X-704750Y-569467D01*
Y-568533D01*
X-704583Y-567600D01*
X-704250Y-566783D01*
X-703750Y-566083D01*
X-703167Y-565617D01*
X-702500Y-565500D01*
X-701833Y-565617D01*
X-701250Y-566083D01*
X-700750Y-566783D01*
X-700417Y-567600D01*
X-700250Y-568533D01*
Y-569467D01*
X-700417Y-570400D01*
X-700750Y-571217D01*
X-701250Y-571917D01*
X-701833Y-572383D01*
X-702500Y-572500D01*
G01X-697367D02*
Y-565500D01*
X-695283D01*
X-694617Y-565850D01*
X-694200Y-566317D01*
X-694033Y-567250D01*
X-694200Y-568183D01*
X-694700Y-568767D01*
X-695283Y-569117D01*
X-697367D01*
G01X-695283D02*
X-694033Y-572500D01*
G01X-684600Y-565500D02*
X-683433Y-572500D01*
X-682100Y-565500D01*
X-680767Y-572500D01*
X-679600Y-565500D01*
G01X-676967Y-572500D02*
Y-565500D01*
X-674883D01*
X-674217Y-565850D01*
X-673800Y-566317D01*
X-673633Y-567250D01*
X-673800Y-568183D01*
X-674300Y-568767D01*
X-674883Y-569117D01*
X-676967D01*
G01X-674883D02*
X-673633Y-572500D01*
G01X-669500Y-565500D02*
X-667500D01*
G01X-668500D02*
Y-572500D01*
G01X-669500D02*
X-667500D01*
G01X-661700Y-565500D02*
Y-572500D01*
G01X-663617Y-565500D02*
X-659783D01*
G01X-654900D02*
Y-572500D01*
G01X-656817Y-565500D02*
X-652983D01*
G01X-646433Y-572500D02*
X-649767D01*
Y-565500D01*
X-646433D01*
G01X-647767Y-568883D02*
X-649767D01*
G01X-643217Y-572500D02*
Y-565500D01*
X-639383Y-572500D01*
Y-565500D01*
G01X-625867Y-566083D02*
X-626367Y-565733D01*
X-626950Y-565500D01*
X-627617D01*
X-628367Y-565850D01*
X-628950Y-566433D01*
X-629367Y-567133D01*
X-629700Y-568300D01*
X-629783Y-569350D01*
X-629617Y-570400D01*
X-629367Y-571100D01*
X-628867Y-571800D01*
X-628283Y-572267D01*
X-627700Y-572500D01*
X-627117D01*
X-626533Y-572267D01*
X-626033Y-571917D01*
X-625617Y-571450D01*
G01X-620900Y-572500D02*
X-621567Y-572383D01*
X-622150Y-571917D01*
X-622650Y-571217D01*
X-622983Y-570400D01*
X-623150Y-569467D01*
Y-568533D01*
X-622983Y-567600D01*
X-622650Y-566783D01*
X-622150Y-566083D01*
X-621567Y-565617D01*
X-620900Y-565500D01*
X-620233Y-565617D01*
X-619650Y-566083D01*
X-619150Y-566783D01*
X-618817Y-567600D01*
X-618650Y-568533D01*
Y-569467D01*
X-618817Y-570400D01*
X-619150Y-571217D01*
X-619650Y-571917D01*
X-620233Y-572383D01*
X-620900Y-572500D01*
G01X-616017D02*
Y-565500D01*
X-612183Y-572500D01*
Y-565500D01*
G01X-609050Y-571567D02*
X-608383Y-572150D01*
X-607633Y-572500D01*
X-606967D01*
X-606300Y-572150D01*
X-605800Y-571567D01*
X-605550Y-570750D01*
X-605717Y-569933D01*
X-606133Y-569233D01*
X-606883Y-568767D01*
X-607883Y-568533D01*
X-608467Y-568067D01*
X-608717Y-567250D01*
X-608550Y-566433D01*
X-608133Y-565850D01*
X-607550Y-565500D01*
X-606967D01*
X-606383Y-565733D01*
X-605883Y-566317D01*
G01X-598833Y-572500D02*
X-602167D01*
Y-565500D01*
X-598833D01*
G01X-600167Y-568883D02*
X-602167D01*
G01X-595617Y-572500D02*
Y-565500D01*
X-591783Y-572500D01*
Y-565500D01*
G01X-586900D02*
Y-572500D01*
G01X-588817Y-565500D02*
X-584983D01*
G01X-872500Y-587500D02*
X-873167Y-587383D01*
X-873750Y-586917D01*
X-874250Y-586217D01*
X-874583Y-585400D01*
X-874750Y-584467D01*
Y-583533D01*
X-874583Y-582600D01*
X-874250Y-581783D01*
X-873750Y-581083D01*
X-873167Y-580617D01*
X-872500Y-580500D01*
X-871833Y-580617D01*
X-871250Y-581083D01*
X-870750Y-581783D01*
X-870417Y-582600D01*
X-870250Y-583533D01*
Y-584467D01*
X-870417Y-585400D01*
X-870750Y-586217D01*
X-871250Y-586917D01*
X-871833Y-587383D01*
X-872500Y-587500D01*
G01X-867283D02*
Y-580500D01*
X-864117D01*
G01X-865283Y-583883D02*
X-867283D01*
G01X-854267Y-587500D02*
Y-580500D01*
X-852100Y-586333D01*
X-849933Y-580500D01*
Y-587500D01*
G01X-846300Y-580500D02*
X-844300D01*
G01X-845300D02*
Y-587500D01*
G01X-846300D02*
X-844300D01*
G01X-836667Y-581083D02*
X-837167Y-580733D01*
X-837750Y-580500D01*
X-838417D01*
X-839167Y-580850D01*
X-839750Y-581433D01*
X-840167Y-582133D01*
X-840500Y-583300D01*
X-840583Y-584350D01*
X-840417Y-585400D01*
X-840167Y-586100D01*
X-839667Y-586800D01*
X-839083Y-587267D01*
X-838500Y-587500D01*
X-837917D01*
X-837333Y-587267D01*
X-836833Y-586917D01*
X-836417Y-586450D01*
G01X-833367Y-587500D02*
Y-580500D01*
X-831283D01*
X-830617Y-580850D01*
X-830200Y-581317D01*
X-830033Y-582250D01*
X-830200Y-583183D01*
X-830700Y-583767D01*
X-831283Y-584117D01*
X-833367D01*
G01X-831283D02*
X-830033Y-587500D01*
G01X-824900D02*
X-825567Y-587383D01*
X-826150Y-586917D01*
X-826650Y-586217D01*
X-826983Y-585400D01*
X-827150Y-584467D01*
Y-583533D01*
X-826983Y-582600D01*
X-826650Y-581783D01*
X-826150Y-581083D01*
X-825567Y-580617D01*
X-824900Y-580500D01*
X-824233Y-580617D01*
X-823650Y-581083D01*
X-823150Y-581783D01*
X-822817Y-582600D01*
X-822650Y-583533D01*
Y-584467D01*
X-822817Y-585400D01*
X-823150Y-586217D01*
X-823650Y-586917D01*
X-824233Y-587383D01*
X-824900Y-587500D01*
G01X-819850Y-586567D02*
X-819183Y-587150D01*
X-818433Y-587500D01*
X-817767D01*
X-817100Y-587150D01*
X-816600Y-586567D01*
X-816350Y-585750D01*
X-816517Y-584933D01*
X-816933Y-584233D01*
X-817683Y-583767D01*
X-818683Y-583533D01*
X-819267Y-583067D01*
X-819517Y-582250D01*
X-819350Y-581433D01*
X-818933Y-580850D01*
X-818350Y-580500D01*
X-817767D01*
X-817183Y-580733D01*
X-816683Y-581317D01*
G01X-811300Y-587500D02*
X-811967Y-587383D01*
X-812550Y-586917D01*
X-813050Y-586217D01*
X-813383Y-585400D01*
X-813550Y-584467D01*
Y-583533D01*
X-813383Y-582600D01*
X-813050Y-581783D01*
X-812550Y-581083D01*
X-811967Y-580617D01*
X-811300Y-580500D01*
X-810633Y-580617D01*
X-810050Y-581083D01*
X-809550Y-581783D01*
X-809217Y-582600D01*
X-809050Y-583533D01*
Y-584467D01*
X-809217Y-585400D01*
X-809550Y-586217D01*
X-810050Y-586917D01*
X-810633Y-587383D01*
X-811300Y-587500D01*
G01X-806083D02*
Y-580500D01*
X-802917D01*
G01X-804083Y-583883D02*
X-806083D01*
G01X-797700Y-580500D02*
Y-587500D01*
G01X-799617Y-580500D02*
X-795783D01*
G01X-782267Y-581083D02*
X-782767Y-580733D01*
X-783350Y-580500D01*
X-784017D01*
X-784767Y-580850D01*
X-785350Y-581433D01*
X-785767Y-582133D01*
X-786100Y-583300D01*
X-786183Y-584350D01*
X-786017Y-585400D01*
X-785767Y-586100D01*
X-785267Y-586800D01*
X-784683Y-587267D01*
X-784100Y-587500D01*
X-783517D01*
X-782933Y-587267D01*
X-782433Y-586917D01*
X-782017Y-586450D01*
G01X-777300Y-587500D02*
X-777967Y-587383D01*
X-778550Y-586917D01*
X-779050Y-586217D01*
X-779383Y-585400D01*
X-779550Y-584467D01*
Y-583533D01*
X-779383Y-582600D01*
X-779050Y-581783D01*
X-778550Y-581083D01*
X-777967Y-580617D01*
X-777300Y-580500D01*
X-776633Y-580617D01*
X-776050Y-581083D01*
X-775550Y-581783D01*
X-775217Y-582600D01*
X-775050Y-583533D01*
Y-584467D01*
X-775217Y-585400D01*
X-775550Y-586217D01*
X-776050Y-586917D01*
X-776633Y-587383D01*
X-777300Y-587500D01*
G01X-772167D02*
Y-580500D01*
X-770083D01*
X-769417Y-580850D01*
X-769000Y-581317D01*
X-768833Y-582250D01*
X-769000Y-583183D01*
X-769500Y-583767D01*
X-770083Y-584117D01*
X-772167D01*
G01X-770083D02*
X-768833Y-587500D01*
G01X-765367D02*
Y-580500D01*
X-763367D01*
X-762700Y-580850D01*
X-762200Y-581667D01*
X-762033Y-582600D01*
X-762200Y-583533D01*
X-762617Y-584233D01*
X-763367Y-584584D01*
X-765367D01*
G01X-756900Y-587500D02*
X-757567Y-587383D01*
X-758150Y-586917D01*
X-758650Y-586217D01*
X-758983Y-585400D01*
X-759150Y-584467D01*
Y-583533D01*
X-758983Y-582600D01*
X-758650Y-581783D01*
X-758150Y-581083D01*
X-757567Y-580617D01*
X-756900Y-580500D01*
X-756233Y-580617D01*
X-755650Y-581083D01*
X-755150Y-581783D01*
X-754817Y-582600D01*
X-754650Y-583533D01*
Y-584467D01*
X-754817Y-585400D01*
X-755150Y-586217D01*
X-755650Y-586917D01*
X-756233Y-587383D01*
X-756900Y-587500D01*
G01X-751767D02*
Y-580500D01*
X-749683D01*
X-749017Y-580850D01*
X-748600Y-581317D01*
X-748433Y-582250D01*
X-748600Y-583183D01*
X-749100Y-583767D01*
X-749683Y-584117D01*
X-751767D01*
G01X-749683D02*
X-748433Y-587500D01*
G01X-745383D02*
X-743300Y-580500D01*
X-741217Y-587500D01*
G01X-741967Y-585050D02*
X-744633D01*
G01X-736500Y-580500D02*
Y-587500D01*
G01X-738417Y-580500D02*
X-734583D01*
G01X-730700D02*
X-728700D01*
G01X-729700D02*
Y-587500D01*
G01X-730700D02*
X-728700D01*
G01X-722900D02*
X-723567Y-587383D01*
X-724150Y-586917D01*
X-724650Y-586217D01*
X-724983Y-585400D01*
X-725150Y-584467D01*
Y-583533D01*
X-724983Y-582600D01*
X-724650Y-581783D01*
X-724150Y-581083D01*
X-723567Y-580617D01*
X-722900Y-580500D01*
X-722233Y-580617D01*
X-721650Y-581083D01*
X-721150Y-581783D01*
X-720817Y-582600D01*
X-720650Y-583533D01*
Y-584467D01*
X-720817Y-585400D01*
X-721150Y-586217D01*
X-721650Y-586917D01*
X-722233Y-587383D01*
X-722900Y-587500D01*
G01X-718017D02*
Y-580500D01*
X-714183Y-587500D01*
Y-580500D01*
G01X-709300Y-587733D02*
X-709467Y-587617D01*
Y-587383D01*
X-709300Y-587267D01*
X-709133Y-587383D01*
Y-587617D01*
X-709300Y-587733D01*
G01X-870667Y-551083D02*
X-871167Y-550733D01*
X-871750Y-550500D01*
X-872417D01*
X-873167Y-550850D01*
X-873750Y-551433D01*
X-874167Y-552133D01*
X-874500Y-553300D01*
X-874583Y-554350D01*
X-874417Y-555400D01*
X-874167Y-556100D01*
X-873667Y-556800D01*
X-873083Y-557267D01*
X-872500Y-557500D01*
X-871917D01*
X-871333Y-557267D01*
X-870833Y-556917D01*
X-870417Y-556450D01*
G01X-865700Y-557500D02*
X-866367Y-557383D01*
X-866950Y-556917D01*
X-867450Y-556217D01*
X-867783Y-555400D01*
X-867950Y-554467D01*
Y-553533D01*
X-867783Y-552600D01*
X-867450Y-551783D01*
X-866950Y-551083D01*
X-866367Y-550617D01*
X-865700Y-550500D01*
X-865033Y-550617D01*
X-864450Y-551083D01*
X-863950Y-551783D01*
X-863617Y-552600D01*
X-863450Y-553533D01*
Y-554467D01*
X-863617Y-555400D01*
X-863950Y-556217D01*
X-864450Y-556917D01*
X-865033Y-557383D01*
X-865700Y-557500D01*
G01X-860817D02*
Y-550500D01*
X-856983Y-557500D01*
Y-550500D01*
G01X-853683Y-557500D02*
Y-550500D01*
X-850517D01*
G01X-851683Y-553883D02*
X-853683D01*
G01X-846300Y-550500D02*
X-844300D01*
G01X-845300D02*
Y-557500D01*
G01X-846300D02*
X-844300D01*
G01X-840333D02*
Y-550500D01*
X-838667D01*
X-838000Y-550850D01*
X-837500Y-551317D01*
X-837083Y-552017D01*
X-836750Y-552833D01*
X-836667Y-554000D01*
X-836750Y-555167D01*
X-837083Y-555983D01*
X-837500Y-556684D01*
X-838000Y-557150D01*
X-838667Y-557500D01*
X-840333D01*
G01X-830033D02*
X-833367D01*
Y-550500D01*
X-830033D01*
G01X-831367Y-553883D02*
X-833367D01*
G01X-826817Y-557500D02*
Y-550500D01*
X-822983Y-557500D01*
Y-550500D01*
G01X-816267Y-551083D02*
X-816767Y-550733D01*
X-817350Y-550500D01*
X-818017D01*
X-818767Y-550850D01*
X-819350Y-551433D01*
X-819767Y-552133D01*
X-820100Y-553300D01*
X-820183Y-554350D01*
X-820017Y-555400D01*
X-819767Y-556100D01*
X-819267Y-556800D01*
X-818683Y-557267D01*
X-818100Y-557500D01*
X-817517D01*
X-816933Y-557267D01*
X-816433Y-556917D01*
X-816017Y-556450D01*
G01X-809633Y-557500D02*
X-812967D01*
Y-550500D01*
X-809633D01*
G01X-810967Y-553883D02*
X-812967D01*
G01X-799783Y-557500D02*
X-797700Y-550500D01*
X-795617Y-557500D01*
G01X-796367Y-555050D02*
X-799033D01*
G01X-792817Y-557500D02*
Y-550500D01*
X-788983Y-557500D01*
Y-550500D01*
G01X-785933Y-557500D02*
Y-550500D01*
X-784267D01*
X-783600Y-550850D01*
X-783100Y-551317D01*
X-782683Y-552017D01*
X-782350Y-552833D01*
X-782267Y-554000D01*
X-782350Y-555167D01*
X-782683Y-555983D01*
X-783100Y-556684D01*
X-783600Y-557150D01*
X-784267Y-557500D01*
X-785933D01*
G01X-771500Y-550500D02*
X-769500D01*
G01X-770500D02*
Y-557500D01*
G01X-771500D02*
X-769500D01*
G01X-763700Y-550500D02*
Y-557500D01*
G01X-765617Y-550500D02*
X-761783D01*
G01X-758650Y-556567D02*
X-757983Y-557150D01*
X-757233Y-557500D01*
X-756567D01*
X-755900Y-557150D01*
X-755400Y-556567D01*
X-755150Y-555750D01*
X-755317Y-554933D01*
X-755733Y-554233D01*
X-756483Y-553767D01*
X-757483Y-553533D01*
X-758067Y-553067D01*
X-758317Y-552250D01*
X-758150Y-551433D01*
X-757733Y-550850D01*
X-757150Y-550500D01*
X-756567D01*
X-755983Y-550733D01*
X-755483Y-551317D01*
G01X-741467Y-551083D02*
X-741967Y-550733D01*
X-742550Y-550500D01*
X-743217D01*
X-743967Y-550850D01*
X-744550Y-551433D01*
X-744967Y-552133D01*
X-745300Y-553300D01*
X-745383Y-554350D01*
X-745217Y-555400D01*
X-744967Y-556100D01*
X-744467Y-556800D01*
X-743883Y-557267D01*
X-743300Y-557500D01*
X-742717D01*
X-742133Y-557267D01*
X-741633Y-556917D01*
X-741217Y-556450D01*
G01X-736500Y-557500D02*
X-737167Y-557383D01*
X-737750Y-556917D01*
X-738250Y-556217D01*
X-738583Y-555400D01*
X-738750Y-554467D01*
Y-553533D01*
X-738583Y-552600D01*
X-738250Y-551783D01*
X-737750Y-551083D01*
X-737167Y-550617D01*
X-736500Y-550500D01*
X-735833Y-550617D01*
X-735250Y-551083D01*
X-734750Y-551783D01*
X-734417Y-552600D01*
X-734250Y-553533D01*
Y-554467D01*
X-734417Y-555400D01*
X-734750Y-556217D01*
X-735250Y-556917D01*
X-735833Y-557383D01*
X-736500Y-557500D01*
G01X-731617D02*
Y-550500D01*
X-727783Y-557500D01*
Y-550500D01*
G01X-722900D02*
Y-557500D01*
G01X-724817Y-550500D02*
X-720983D01*
G01X-714433Y-557500D02*
X-717767D01*
Y-550500D01*
X-714433D01*
G01X-715767Y-553883D02*
X-717767D01*
G01X-711217Y-557500D02*
Y-550500D01*
X-707383Y-557500D01*
Y-550500D01*
G01X-702500D02*
Y-557500D01*
G01X-704417Y-550500D02*
X-700583D01*
G01X-697450Y-556567D02*
X-696783Y-557150D01*
X-696033Y-557500D01*
X-695367D01*
X-694700Y-557150D01*
X-694200Y-556567D01*
X-693950Y-555750D01*
X-694117Y-554933D01*
X-694533Y-554233D01*
X-695283Y-553767D01*
X-696283Y-553533D01*
X-696867Y-553067D01*
X-697117Y-552250D01*
X-696950Y-551433D01*
X-696533Y-550850D01*
X-695950Y-550500D01*
X-695367D01*
X-694783Y-550733D01*
X-694283Y-551317D01*
G01X-684267Y-557500D02*
Y-550500D01*
X-682100Y-556333D01*
X-679933Y-550500D01*
Y-557500D01*
G01X-677383D02*
X-675300Y-550500D01*
X-673217Y-557500D01*
G01X-673967Y-555050D02*
X-676633D01*
G01X-668500Y-557500D02*
Y-554350D01*
X-670167Y-550500D01*
G01X-666833D02*
X-668500Y-554350D01*
G01X-656817Y-557500D02*
Y-550500D01*
X-652983Y-557500D01*
Y-550500D01*
G01X-648100Y-557500D02*
X-648767Y-557383D01*
X-649350Y-556917D01*
X-649850Y-556217D01*
X-650183Y-555400D01*
X-650350Y-554467D01*
Y-553533D01*
X-650183Y-552600D01*
X-649850Y-551783D01*
X-649350Y-551083D01*
X-648767Y-550617D01*
X-648100Y-550500D01*
X-647433Y-550617D01*
X-646850Y-551083D01*
X-646350Y-551783D01*
X-646017Y-552600D01*
X-645850Y-553533D01*
Y-554467D01*
X-646017Y-555400D01*
X-646350Y-556217D01*
X-646850Y-556917D01*
X-647433Y-557383D01*
X-648100Y-557500D01*
G01X-641300Y-550500D02*
Y-557500D01*
G01X-643217Y-550500D02*
X-639383D01*
G01X-627033Y-553767D02*
X-626700Y-553417D01*
X-626450Y-552833D01*
X-626283Y-552017D01*
X-626450Y-551317D01*
X-626783Y-550850D01*
X-627367Y-550500D01*
X-629617D01*
Y-557500D01*
X-626867D01*
X-626283Y-557033D01*
X-625950Y-556333D01*
X-625783Y-555517D01*
X-625950Y-554700D01*
X-626450Y-554000D01*
X-627033Y-553767D01*
X-629617D01*
G01X-619233Y-557500D02*
X-622567D01*
Y-550500D01*
X-619233D01*
G01X-620567Y-553883D02*
X-622567D01*
G01X-870667Y-536083D02*
X-871167Y-535733D01*
X-871750Y-535500D01*
X-872417D01*
X-873167Y-535850D01*
X-873750Y-536433D01*
X-874167Y-537133D01*
X-874500Y-538300D01*
X-874583Y-539350D01*
X-874417Y-540400D01*
X-874167Y-541100D01*
X-873667Y-541800D01*
X-873083Y-542267D01*
X-872500Y-542500D01*
X-871917D01*
X-871333Y-542267D01*
X-870833Y-541917D01*
X-870417Y-541450D01*
G01X-865700Y-542500D02*
X-866367Y-542383D01*
X-866950Y-541917D01*
X-867450Y-541217D01*
X-867783Y-540400D01*
X-867950Y-539467D01*
Y-538533D01*
X-867783Y-537600D01*
X-867450Y-536783D01*
X-866950Y-536083D01*
X-866367Y-535617D01*
X-865700Y-535500D01*
X-865033Y-535617D01*
X-864450Y-536083D01*
X-863950Y-536783D01*
X-863617Y-537600D01*
X-863450Y-538533D01*
Y-539467D01*
X-863617Y-540400D01*
X-863950Y-541217D01*
X-864450Y-541917D01*
X-865033Y-542383D01*
X-865700Y-542500D01*
G01X-860567D02*
Y-535500D01*
X-858483D01*
X-857817Y-535850D01*
X-857400Y-536317D01*
X-857233Y-537250D01*
X-857400Y-538183D01*
X-857900Y-538767D01*
X-858483Y-539117D01*
X-860567D01*
G01X-858483D02*
X-857233Y-542500D01*
G01X-853767D02*
Y-535500D01*
X-851767D01*
X-851100Y-535850D01*
X-850600Y-536667D01*
X-850433Y-537600D01*
X-850600Y-538533D01*
X-851017Y-539233D01*
X-851767Y-539584D01*
X-853767D01*
G01X-845300Y-542500D02*
X-845967Y-542383D01*
X-846550Y-541917D01*
X-847050Y-541217D01*
X-847383Y-540400D01*
X-847550Y-539467D01*
Y-538533D01*
X-847383Y-537600D01*
X-847050Y-536783D01*
X-846550Y-536083D01*
X-845967Y-535617D01*
X-845300Y-535500D01*
X-844633Y-535617D01*
X-844050Y-536083D01*
X-843550Y-536783D01*
X-843217Y-537600D01*
X-843050Y-538533D01*
Y-539467D01*
X-843217Y-540400D01*
X-843550Y-541217D01*
X-844050Y-541917D01*
X-844633Y-542383D01*
X-845300Y-542500D01*
G01X-840167D02*
Y-535500D01*
X-838083D01*
X-837417Y-535850D01*
X-837000Y-536317D01*
X-836833Y-537250D01*
X-837000Y-538183D01*
X-837500Y-538767D01*
X-838083Y-539117D01*
X-840167D01*
G01X-838083D02*
X-836833Y-542500D01*
G01X-833783D02*
X-831700Y-535500D01*
X-829617Y-542500D01*
G01X-830367Y-540050D02*
X-833033D01*
G01X-824900Y-535500D02*
Y-542500D01*
G01X-826817Y-535500D02*
X-822983D01*
G01X-819100D02*
X-817100D01*
G01X-818100D02*
Y-542500D01*
G01X-819100D02*
X-817100D01*
G01X-811300D02*
X-811967Y-542383D01*
X-812550Y-541917D01*
X-813050Y-541217D01*
X-813383Y-540400D01*
X-813550Y-539467D01*
Y-538533D01*
X-813383Y-537600D01*
X-813050Y-536783D01*
X-812550Y-536083D01*
X-811967Y-535617D01*
X-811300Y-535500D01*
X-810633Y-535617D01*
X-810050Y-536083D01*
X-809550Y-536783D01*
X-809217Y-537600D01*
X-809050Y-538533D01*
Y-539467D01*
X-809217Y-540400D01*
X-809550Y-541217D01*
X-810050Y-541917D01*
X-810633Y-542383D01*
X-811300Y-542500D01*
G01X-806417D02*
Y-535500D01*
X-802583Y-542500D01*
Y-535500D01*
G01X-797700Y-542733D02*
X-797867Y-542617D01*
Y-542383D01*
X-797700Y-542267D01*
X-797533Y-542383D01*
Y-542617D01*
X-797700Y-542733D01*
G01X-784100Y-535500D02*
Y-542500D01*
G01X-786017Y-535500D02*
X-782183D01*
G01X-779050Y-542500D02*
Y-535500D01*
G01X-775550D02*
Y-542500D01*
G01Y-539000D02*
X-779050D01*
G01X-771500Y-535500D02*
X-769500D01*
G01X-770500D02*
Y-542500D01*
G01X-771500D02*
X-769500D01*
G01X-765450Y-541567D02*
X-764783Y-542150D01*
X-764033Y-542500D01*
X-763367D01*
X-762700Y-542150D01*
X-762200Y-541567D01*
X-761950Y-540750D01*
X-762117Y-539933D01*
X-762533Y-539233D01*
X-763283Y-538767D01*
X-764283Y-538533D01*
X-764867Y-538067D01*
X-765117Y-537250D01*
X-764950Y-536433D01*
X-764533Y-535850D01*
X-763950Y-535500D01*
X-763367D01*
X-762783Y-535733D01*
X-762283Y-536317D01*
G01X-751933Y-542500D02*
Y-535500D01*
X-750267D01*
X-749600Y-535850D01*
X-749100Y-536317D01*
X-748683Y-537017D01*
X-748350Y-537833D01*
X-748267Y-539000D01*
X-748350Y-540167D01*
X-748683Y-540983D01*
X-749100Y-541684D01*
X-749600Y-542150D01*
X-750267Y-542500D01*
X-751933D01*
G01X-744967D02*
Y-535500D01*
X-742883D01*
X-742217Y-535850D01*
X-741800Y-536317D01*
X-741633Y-537250D01*
X-741800Y-538183D01*
X-742300Y-538767D01*
X-742883Y-539117D01*
X-744967D01*
G01X-742883D02*
X-741633Y-542500D01*
G01X-738583D02*
X-736500Y-535500D01*
X-734417Y-542500D01*
G01X-735167Y-540050D02*
X-737833D01*
G01X-732200Y-535500D02*
X-731033Y-542500D01*
X-729700Y-535500D01*
X-728367Y-542500D01*
X-727200Y-535500D01*
G01X-723900D02*
X-721900D01*
G01X-722900D02*
Y-542500D01*
G01X-723900D02*
X-721900D01*
G01X-718017D02*
Y-535500D01*
X-714183Y-542500D01*
Y-535500D01*
G01X-708800Y-539000D02*
X-707133D01*
Y-541100D01*
X-707633Y-541800D01*
X-708217Y-542267D01*
X-709050Y-542500D01*
X-709883Y-542267D01*
X-710467Y-541800D01*
X-710967Y-541100D01*
X-711300Y-540283D01*
X-711467Y-539350D01*
Y-538533D01*
X-711300Y-537833D01*
X-710967Y-537017D01*
X-710467Y-536317D01*
X-709967Y-535850D01*
X-709300Y-535500D01*
X-708717D01*
X-708050Y-535733D01*
X-707550Y-536200D01*
G01X-696700Y-535500D02*
X-694700D01*
G01X-695700D02*
Y-542500D01*
G01X-696700D02*
X-694700D01*
G01X-690650Y-541567D02*
X-689983Y-542150D01*
X-689233Y-542500D01*
X-688567D01*
X-687900Y-542150D01*
X-687400Y-541567D01*
X-687150Y-540750D01*
X-687317Y-539933D01*
X-687733Y-539233D01*
X-688483Y-538767D01*
X-689483Y-538533D01*
X-690067Y-538067D01*
X-690317Y-537250D01*
X-690150Y-536433D01*
X-689733Y-535850D01*
X-689150Y-535500D01*
X-688567D01*
X-687983Y-535733D01*
X-687483Y-536317D01*
G01X-676967Y-542500D02*
Y-535500D01*
X-674883D01*
X-674217Y-535850D01*
X-673800Y-536317D01*
X-673633Y-537250D01*
X-673800Y-538183D01*
X-674300Y-538767D01*
X-674883Y-539117D01*
X-676967D01*
G01X-674883D02*
X-673633Y-542500D01*
G01X-666833D02*
X-670167D01*
Y-535500D01*
X-666833D01*
G01X-668167Y-538883D02*
X-670167D01*
G01X-659867Y-536083D02*
X-660367Y-535733D01*
X-660950Y-535500D01*
X-661617D01*
X-662367Y-535850D01*
X-662950Y-536433D01*
X-663367Y-537133D01*
X-663700Y-538300D01*
X-663783Y-539350D01*
X-663617Y-540400D01*
X-663367Y-541100D01*
X-662867Y-541800D01*
X-662283Y-542267D01*
X-661700Y-542500D01*
X-661117D01*
X-660533Y-542267D01*
X-660033Y-541917D01*
X-659617Y-541450D01*
G01X-653233Y-542500D02*
X-656567D01*
Y-535500D01*
X-653233D01*
G01X-654567Y-538883D02*
X-656567D01*
G01X-649100Y-535500D02*
X-647100D01*
G01X-648100D02*
Y-542500D01*
G01X-649100D02*
X-647100D01*
G01X-643383Y-535500D02*
X-641300Y-542500D01*
X-639217Y-535500D01*
G01X-632833Y-542500D02*
X-636167D01*
Y-535500D01*
X-632833D01*
G01X-634167Y-538883D02*
X-636167D01*
G01X-629533Y-542500D02*
Y-535500D01*
X-627867D01*
X-627200Y-535850D01*
X-626700Y-536317D01*
X-626283Y-537017D01*
X-625950Y-537833D01*
X-625867Y-539000D01*
X-625950Y-540167D01*
X-626283Y-540983D01*
X-626700Y-541684D01*
X-627200Y-542150D01*
X-627867Y-542500D01*
X-629533D01*
G01X-615100Y-535500D02*
X-613100D01*
G01X-614100D02*
Y-542500D01*
G01X-615100D02*
X-613100D01*
G01X-609217D02*
Y-535500D01*
X-605383Y-542500D01*
Y-535500D01*
G01X-872500Y-520500D02*
Y-527500D01*
G01X-874417Y-520500D02*
X-870583D01*
G01X-867450Y-527500D02*
Y-520500D01*
G01X-863950D02*
Y-527500D01*
G01Y-524000D02*
X-867450D01*
G01X-857233Y-527500D02*
X-860567D01*
Y-520500D01*
X-857233D01*
G01X-858567Y-523883D02*
X-860567D01*
G01X-846967Y-527500D02*
Y-520500D01*
X-844967D01*
X-844300Y-520850D01*
X-843800Y-521667D01*
X-843633Y-522600D01*
X-843800Y-523533D01*
X-844217Y-524233D01*
X-844967Y-524584D01*
X-846967D01*
G01X-840167Y-527500D02*
Y-520500D01*
X-838083D01*
X-837417Y-520850D01*
X-837000Y-521317D01*
X-836833Y-522250D01*
X-837000Y-523183D01*
X-837500Y-523767D01*
X-838083Y-524117D01*
X-840167D01*
G01X-838083D02*
X-836833Y-527500D01*
G01X-831700D02*
X-832367Y-527383D01*
X-832950Y-526917D01*
X-833450Y-526217D01*
X-833783Y-525400D01*
X-833950Y-524467D01*
Y-523533D01*
X-833783Y-522600D01*
X-833450Y-521783D01*
X-832950Y-521083D01*
X-832367Y-520617D01*
X-831700Y-520500D01*
X-831033Y-520617D01*
X-830450Y-521083D01*
X-829950Y-521783D01*
X-829617Y-522600D01*
X-829450Y-523533D01*
Y-524467D01*
X-829617Y-525400D01*
X-829950Y-526217D01*
X-830450Y-526917D01*
X-831033Y-527383D01*
X-831700Y-527500D01*
G01X-826567D02*
Y-520500D01*
X-824567D01*
X-823900Y-520850D01*
X-823400Y-521667D01*
X-823233Y-522600D01*
X-823400Y-523533D01*
X-823817Y-524233D01*
X-824567Y-524584D01*
X-826567D01*
G01X-819767Y-527500D02*
Y-520500D01*
X-817683D01*
X-817017Y-520850D01*
X-816600Y-521317D01*
X-816433Y-522250D01*
X-816600Y-523183D01*
X-817100Y-523767D01*
X-817683Y-524117D01*
X-819767D01*
G01X-817683D02*
X-816433Y-527500D01*
G01X-812300Y-520500D02*
X-810300D01*
G01X-811300D02*
Y-527500D01*
G01X-812300D02*
X-810300D01*
G01X-802833D02*
X-806167D01*
Y-520500D01*
X-802833D01*
G01X-804167Y-523883D02*
X-806167D01*
G01X-797700Y-520500D02*
Y-527500D01*
G01X-799617Y-520500D02*
X-795783D01*
G01X-792983Y-527500D02*
X-790900Y-520500D01*
X-788817Y-527500D01*
G01X-789567Y-525050D02*
X-792233D01*
G01X-785767Y-527500D02*
Y-520500D01*
X-783683D01*
X-783017Y-520850D01*
X-782600Y-521317D01*
X-782433Y-522250D01*
X-782600Y-523183D01*
X-783100Y-523767D01*
X-783683Y-524117D01*
X-785767D01*
G01X-783683D02*
X-782433Y-527500D01*
G01X-777300D02*
Y-524350D01*
X-778967Y-520500D01*
G01X-775633D02*
X-777300Y-524350D01*
G01X-765367Y-527500D02*
Y-520500D01*
X-763367D01*
X-762700Y-520850D01*
X-762200Y-521667D01*
X-762033Y-522600D01*
X-762200Y-523533D01*
X-762617Y-524233D01*
X-763367Y-524584D01*
X-765367D01*
G01X-758567Y-527500D02*
Y-520500D01*
X-756483D01*
X-755817Y-520850D01*
X-755400Y-521317D01*
X-755233Y-522250D01*
X-755400Y-523183D01*
X-755900Y-523767D01*
X-756483Y-524117D01*
X-758567D01*
G01X-756483D02*
X-755233Y-527500D01*
G01X-750100D02*
X-750767Y-527383D01*
X-751350Y-526917D01*
X-751850Y-526217D01*
X-752183Y-525400D01*
X-752350Y-524467D01*
Y-523533D01*
X-752183Y-522600D01*
X-751850Y-521783D01*
X-751350Y-521083D01*
X-750767Y-520617D01*
X-750100Y-520500D01*
X-749433Y-520617D01*
X-748850Y-521083D01*
X-748350Y-521783D01*
X-748017Y-522600D01*
X-747850Y-523533D01*
Y-524467D01*
X-748017Y-525400D01*
X-748350Y-526217D01*
X-748850Y-526917D01*
X-749433Y-527383D01*
X-750100Y-527500D01*
G01X-744967D02*
Y-520500D01*
X-742967D01*
X-742300Y-520850D01*
X-741800Y-521667D01*
X-741633Y-522600D01*
X-741800Y-523533D01*
X-742217Y-524233D01*
X-742967Y-524584D01*
X-744967D01*
G01X-734833Y-527500D02*
X-738167D01*
Y-520500D01*
X-734833D01*
G01X-736167Y-523883D02*
X-738167D01*
G01X-731367Y-527500D02*
Y-520500D01*
X-729283D01*
X-728617Y-520850D01*
X-728200Y-521317D01*
X-728033Y-522250D01*
X-728200Y-523183D01*
X-728700Y-523767D01*
X-729283Y-524117D01*
X-731367D01*
G01X-729283D02*
X-728033Y-527500D01*
G01X-722900Y-520500D02*
Y-527500D01*
G01X-724817Y-520500D02*
X-720983D01*
G01X-716100Y-527500D02*
Y-524350D01*
X-717767Y-520500D01*
G01X-714433D02*
X-716100Y-524350D01*
G01X-702500Y-527500D02*
X-703167Y-527383D01*
X-703750Y-526917D01*
X-704250Y-526217D01*
X-704583Y-525400D01*
X-704750Y-524467D01*
Y-523533D01*
X-704583Y-522600D01*
X-704250Y-521783D01*
X-703750Y-521083D01*
X-703167Y-520617D01*
X-702500Y-520500D01*
X-701833Y-520617D01*
X-701250Y-521083D01*
X-700750Y-521783D01*
X-700417Y-522600D01*
X-700250Y-523533D01*
Y-524467D01*
X-700417Y-525400D01*
X-700750Y-526217D01*
X-701250Y-526917D01*
X-701833Y-527383D01*
X-702500Y-527500D01*
G01X-697283D02*
Y-520500D01*
X-694117D01*
G01X-695283Y-523883D02*
X-697283D01*
G01X-684267Y-527500D02*
Y-520500D01*
X-682100Y-526333D01*
X-679933Y-520500D01*
Y-527500D01*
G01X-676300Y-520500D02*
X-674300D01*
G01X-675300D02*
Y-527500D01*
G01X-676300D02*
X-674300D01*
G01X-666667Y-521083D02*
X-667167Y-520733D01*
X-667750Y-520500D01*
X-668417D01*
X-669167Y-520850D01*
X-669750Y-521433D01*
X-670167Y-522133D01*
X-670500Y-523300D01*
X-670583Y-524350D01*
X-670417Y-525400D01*
X-670167Y-526100D01*
X-669667Y-526800D01*
X-669083Y-527267D01*
X-668500Y-527500D01*
X-667917D01*
X-667333Y-527267D01*
X-666833Y-526917D01*
X-666417Y-526450D01*
G01X-663367Y-527500D02*
Y-520500D01*
X-661283D01*
X-660617Y-520850D01*
X-660200Y-521317D01*
X-660033Y-522250D01*
X-660200Y-523183D01*
X-660700Y-523767D01*
X-661283Y-524117D01*
X-663367D01*
G01X-661283D02*
X-660033Y-527500D01*
G01X-654900D02*
X-655567Y-527383D01*
X-656150Y-526917D01*
X-656650Y-526217D01*
X-656983Y-525400D01*
X-657150Y-524467D01*
Y-523533D01*
X-656983Y-522600D01*
X-656650Y-521783D01*
X-656150Y-521083D01*
X-655567Y-520617D01*
X-654900Y-520500D01*
X-654233Y-520617D01*
X-653650Y-521083D01*
X-653150Y-521783D01*
X-652817Y-522600D01*
X-652650Y-523533D01*
Y-524467D01*
X-652817Y-525400D01*
X-653150Y-526217D01*
X-653650Y-526917D01*
X-654233Y-527383D01*
X-654900Y-527500D01*
G01X-649850Y-526567D02*
X-649183Y-527150D01*
X-648433Y-527500D01*
X-647767D01*
X-647100Y-527150D01*
X-646600Y-526567D01*
X-646350Y-525750D01*
X-646517Y-524933D01*
X-646933Y-524233D01*
X-647683Y-523767D01*
X-648683Y-523533D01*
X-649267Y-523067D01*
X-649517Y-522250D01*
X-649350Y-521433D01*
X-648933Y-520850D01*
X-648350Y-520500D01*
X-647767D01*
X-647183Y-520733D01*
X-646683Y-521317D01*
G01X-641300Y-527500D02*
X-641967Y-527383D01*
X-642550Y-526917D01*
X-643050Y-526217D01*
X-643383Y-525400D01*
X-643550Y-524467D01*
Y-523533D01*
X-643383Y-522600D01*
X-643050Y-521783D01*
X-642550Y-521083D01*
X-641967Y-520617D01*
X-641300Y-520500D01*
X-640633Y-520617D01*
X-640050Y-521083D01*
X-639550Y-521783D01*
X-639217Y-522600D01*
X-639050Y-523533D01*
Y-524467D01*
X-639217Y-525400D01*
X-639550Y-526217D01*
X-640050Y-526917D01*
X-640633Y-527383D01*
X-641300Y-527500D01*
G01X-636083D02*
Y-520500D01*
X-632917D01*
G01X-634083Y-523883D02*
X-636083D01*
G01X-627700Y-520500D02*
Y-527500D01*
G01X-629617Y-520500D02*
X-625783D01*
G01X-872500Y-505500D02*
Y-512500D01*
G01X-874417Y-505500D02*
X-870583D01*
G01X-867450Y-512500D02*
Y-505500D01*
G01X-863950D02*
Y-512500D01*
G01Y-509000D02*
X-867450D01*
G01X-859900Y-505500D02*
X-857900D01*
G01X-858900D02*
Y-512500D01*
G01X-859900D02*
X-857900D01*
G01X-853850Y-511567D02*
X-853183Y-512150D01*
X-852433Y-512500D01*
X-851767D01*
X-851100Y-512150D01*
X-850600Y-511567D01*
X-850350Y-510750D01*
X-850517Y-509933D01*
X-850933Y-509233D01*
X-851683Y-508767D01*
X-852683Y-508533D01*
X-853267Y-508067D01*
X-853517Y-507250D01*
X-853350Y-506433D01*
X-852933Y-505850D01*
X-852350Y-505500D01*
X-851767D01*
X-851183Y-505733D01*
X-850683Y-506317D01*
G01X-840333Y-512500D02*
Y-505500D01*
X-838667D01*
X-838000Y-505850D01*
X-837500Y-506317D01*
X-837083Y-507017D01*
X-836750Y-507833D01*
X-836667Y-509000D01*
X-836750Y-510167D01*
X-837083Y-510983D01*
X-837500Y-511684D01*
X-838000Y-512150D01*
X-838667Y-512500D01*
X-840333D01*
G01X-833367D02*
Y-505500D01*
X-831283D01*
X-830617Y-505850D01*
X-830200Y-506317D01*
X-830033Y-507250D01*
X-830200Y-508183D01*
X-830700Y-508767D01*
X-831283Y-509117D01*
X-833367D01*
G01X-831283D02*
X-830033Y-512500D01*
G01X-826983D02*
X-824900Y-505500D01*
X-822817Y-512500D01*
G01X-823567Y-510050D02*
X-826233D01*
G01X-820600Y-505500D02*
X-819433Y-512500D01*
X-818100Y-505500D01*
X-816767Y-512500D01*
X-815600Y-505500D01*
G01X-812300D02*
X-810300D01*
G01X-811300D02*
Y-512500D01*
G01X-812300D02*
X-810300D01*
G01X-806417D02*
Y-505500D01*
X-802583Y-512500D01*
Y-505500D01*
G01X-797200Y-509000D02*
X-795533D01*
Y-511100D01*
X-796033Y-511800D01*
X-796617Y-512267D01*
X-797450Y-512500D01*
X-798283Y-512267D01*
X-798867Y-511800D01*
X-799367Y-511100D01*
X-799700Y-510283D01*
X-799867Y-509350D01*
Y-508533D01*
X-799700Y-507833D01*
X-799367Y-507017D01*
X-798867Y-506317D01*
X-798367Y-505850D01*
X-797700Y-505500D01*
X-797117D01*
X-796450Y-505733D01*
X-795950Y-506200D01*
G01X-782267Y-506083D02*
X-782767Y-505733D01*
X-783350Y-505500D01*
X-784017D01*
X-784767Y-505850D01*
X-785350Y-506433D01*
X-785767Y-507133D01*
X-786100Y-508300D01*
X-786183Y-509350D01*
X-786017Y-510400D01*
X-785767Y-511100D01*
X-785267Y-511800D01*
X-784683Y-512267D01*
X-784100Y-512500D01*
X-783517D01*
X-782933Y-512267D01*
X-782433Y-511917D01*
X-782017Y-511450D01*
G01X-777300Y-512500D02*
X-777967Y-512383D01*
X-778550Y-511917D01*
X-779050Y-511217D01*
X-779383Y-510400D01*
X-779550Y-509467D01*
Y-508533D01*
X-779383Y-507600D01*
X-779050Y-506783D01*
X-778550Y-506083D01*
X-777967Y-505617D01*
X-777300Y-505500D01*
X-776633Y-505617D01*
X-776050Y-506083D01*
X-775550Y-506783D01*
X-775217Y-507600D01*
X-775050Y-508533D01*
Y-509467D01*
X-775217Y-510400D01*
X-775550Y-511217D01*
X-776050Y-511917D01*
X-776633Y-512383D01*
X-777300Y-512500D01*
G01X-772417D02*
Y-505500D01*
X-768583Y-512500D01*
Y-505500D01*
G01X-763700D02*
Y-512500D01*
G01X-765617Y-505500D02*
X-761783D01*
G01X-758983Y-512500D02*
X-756900Y-505500D01*
X-754817Y-512500D01*
G01X-755567Y-510050D02*
X-758233D01*
G01X-751100Y-505500D02*
X-749100D01*
G01X-750100D02*
Y-512500D01*
G01X-751100D02*
X-749100D01*
G01X-745217D02*
Y-505500D01*
X-741383Y-512500D01*
Y-505500D01*
G01X-738250Y-511567D02*
X-737583Y-512150D01*
X-736833Y-512500D01*
X-736167D01*
X-735500Y-512150D01*
X-735000Y-511567D01*
X-734750Y-510750D01*
X-734917Y-509933D01*
X-735333Y-509233D01*
X-736083Y-508767D01*
X-737083Y-508533D01*
X-737667Y-508067D01*
X-737917Y-507250D01*
X-737750Y-506433D01*
X-737333Y-505850D01*
X-736750Y-505500D01*
X-736167D01*
X-735583Y-505733D01*
X-735083Y-506317D01*
G01X-723900Y-505500D02*
X-721900D01*
G01X-722900D02*
Y-512500D01*
G01X-723900D02*
X-721900D01*
G01X-718017D02*
Y-505500D01*
X-714183Y-512500D01*
Y-505500D01*
G01X-710883Y-512500D02*
Y-505500D01*
X-707717D01*
G01X-708883Y-508883D02*
X-710883D01*
G01X-702500Y-512500D02*
X-703167Y-512383D01*
X-703750Y-511917D01*
X-704250Y-511217D01*
X-704583Y-510400D01*
X-704750Y-509467D01*
Y-508533D01*
X-704583Y-507600D01*
X-704250Y-506783D01*
X-703750Y-506083D01*
X-703167Y-505617D01*
X-702500Y-505500D01*
X-701833Y-505617D01*
X-701250Y-506083D01*
X-700750Y-506783D01*
X-700417Y-507600D01*
X-700250Y-508533D01*
Y-509467D01*
X-700417Y-510400D01*
X-700750Y-511217D01*
X-701250Y-511917D01*
X-701833Y-512383D01*
X-702500Y-512500D01*
G01X-697367D02*
Y-505500D01*
X-695283D01*
X-694617Y-505850D01*
X-694200Y-506317D01*
X-694033Y-507250D01*
X-694200Y-508183D01*
X-694700Y-508767D01*
X-695283Y-509117D01*
X-697367D01*
G01X-695283D02*
X-694033Y-512500D01*
G01X-691067D02*
Y-505500D01*
X-688900Y-511333D01*
X-686733Y-505500D01*
Y-512500D01*
G01X-684183D02*
X-682100Y-505500D01*
X-680017Y-512500D01*
G01X-680767Y-510050D02*
X-683433D01*
G01X-675300Y-505500D02*
Y-512500D01*
G01X-677217Y-505500D02*
X-673383D01*
G01X-669500D02*
X-667500D01*
G01X-668500D02*
Y-512500D01*
G01X-669500D02*
X-667500D01*
G01X-661700D02*
X-662367Y-512383D01*
X-662950Y-511917D01*
X-663450Y-511217D01*
X-663783Y-510400D01*
X-663950Y-509467D01*
Y-508533D01*
X-663783Y-507600D01*
X-663450Y-506783D01*
X-662950Y-506083D01*
X-662367Y-505617D01*
X-661700Y-505500D01*
X-661033Y-505617D01*
X-660450Y-506083D01*
X-659950Y-506783D01*
X-659617Y-507600D01*
X-659450Y-508533D01*
Y-509467D01*
X-659617Y-510400D01*
X-659950Y-511217D01*
X-660450Y-511917D01*
X-661033Y-512383D01*
X-661700Y-512500D01*
G01X-656817D02*
Y-505500D01*
X-652983Y-512500D01*
Y-505500D01*
G01X-643800D02*
X-642633Y-512500D01*
X-641300Y-505500D01*
X-639967Y-512500D01*
X-638800Y-505500D01*
G01X-636250Y-512500D02*
Y-505500D01*
G01X-632750D02*
Y-512500D01*
G01Y-509000D02*
X-636250D01*
G01X-628700Y-505500D02*
X-626700D01*
G01X-627700D02*
Y-512500D01*
G01X-628700D02*
X-626700D01*
G01X-619067Y-506083D02*
X-619567Y-505733D01*
X-620150Y-505500D01*
X-620817D01*
X-621567Y-505850D01*
X-622150Y-506433D01*
X-622567Y-507133D01*
X-622900Y-508300D01*
X-622983Y-509350D01*
X-622817Y-510400D01*
X-622567Y-511100D01*
X-622067Y-511800D01*
X-621483Y-512267D01*
X-620900Y-512500D01*
X-620317D01*
X-619733Y-512267D01*
X-619233Y-511917D01*
X-618817Y-511450D01*
G01X-615850Y-512500D02*
Y-505500D01*
G01X-612350D02*
Y-512500D01*
G01Y-509000D02*
X-615850D01*
G01X-601500Y-505500D02*
X-599500D01*
G01X-600500D02*
Y-512500D01*
G01X-601500D02*
X-599500D01*
G01X-595450Y-511567D02*
X-594783Y-512150D01*
X-594033Y-512500D01*
X-593367D01*
X-592700Y-512150D01*
X-592200Y-511567D01*
X-591950Y-510750D01*
X-592117Y-509933D01*
X-592533Y-509233D01*
X-593283Y-508767D01*
X-594283Y-508533D01*
X-594867Y-508067D01*
X-595117Y-507250D01*
X-594950Y-506433D01*
X-594533Y-505850D01*
X-593950Y-505500D01*
X-593367D01*
X-592783Y-505733D01*
X-592283Y-506317D01*
G01X-858133Y-452500D02*
Y-445500D01*
X-856467D01*
X-855800Y-445850D01*
X-855300Y-446317D01*
X-854883Y-447017D01*
X-854550Y-447833D01*
X-854467Y-449000D01*
X-854550Y-450167D01*
X-854883Y-450983D01*
X-855300Y-451684D01*
X-855800Y-452150D01*
X-856467Y-452500D01*
X-858133D01*
G01X-847833D02*
X-851167D01*
Y-445500D01*
X-847833D01*
G01X-849167Y-448883D02*
X-851167D01*
G01X-844450Y-451567D02*
X-843783Y-452150D01*
X-843033Y-452500D01*
X-842367D01*
X-841700Y-452150D01*
X-841200Y-451567D01*
X-840950Y-450750D01*
X-841117Y-449933D01*
X-841533Y-449233D01*
X-842283Y-448767D01*
X-843283Y-448533D01*
X-843867Y-448067D01*
X-844117Y-447250D01*
X-843950Y-446433D01*
X-843533Y-445850D01*
X-842950Y-445500D01*
X-842367D01*
X-841783Y-445733D01*
X-841283Y-446317D01*
G01X-836900Y-445500D02*
X-834900D01*
G01X-835900D02*
Y-452500D01*
G01X-836900D02*
X-834900D01*
G01X-828600Y-449000D02*
X-826933D01*
Y-451100D01*
X-827433Y-451800D01*
X-828017Y-452267D01*
X-828850Y-452500D01*
X-829683Y-452267D01*
X-830267Y-451800D01*
X-830767Y-451100D01*
X-831100Y-450283D01*
X-831267Y-449350D01*
Y-448533D01*
X-831100Y-447833D01*
X-830767Y-447017D01*
X-830267Y-446317D01*
X-829767Y-445850D01*
X-829100Y-445500D01*
X-828517D01*
X-827850Y-445733D01*
X-827350Y-446200D01*
G01X-824217Y-452500D02*
Y-445500D01*
X-820383Y-452500D01*
Y-445500D01*
G01X-813833Y-452500D02*
X-817167D01*
Y-445500D01*
X-813833D01*
G01X-815167Y-448883D02*
X-817167D01*
G01X-810367Y-452500D02*
Y-445500D01*
X-808283D01*
X-807617Y-445850D01*
X-807200Y-446317D01*
X-807033Y-447250D01*
X-807200Y-448183D01*
X-807700Y-448767D01*
X-808283Y-449117D01*
X-810367D01*
G01X-808283D02*
X-807033Y-452500D01*
G01X-858133D02*
Y-445500D01*
X-856467D01*
X-855800Y-445850D01*
X-855300Y-446317D01*
X-854883Y-447017D01*
X-854550Y-447833D01*
X-854467Y-449000D01*
X-854550Y-450167D01*
X-854883Y-450983D01*
X-855300Y-451684D01*
X-855800Y-452150D01*
X-856467Y-452500D01*
X-858133D01*
G01X-847833D02*
X-851167D01*
Y-445500D01*
X-847833D01*
G01X-849167Y-448883D02*
X-851167D01*
G01X-844450Y-451567D02*
X-843783Y-452150D01*
X-843033Y-452500D01*
X-842367D01*
X-841700Y-452150D01*
X-841200Y-451567D01*
X-840950Y-450750D01*
X-841117Y-449933D01*
X-841533Y-449233D01*
X-842283Y-448767D01*
X-843283Y-448533D01*
X-843867Y-448067D01*
X-844117Y-447250D01*
X-843950Y-446433D01*
X-843533Y-445850D01*
X-842950Y-445500D01*
X-842367D01*
X-841783Y-445733D01*
X-841283Y-446317D01*
G01X-836900Y-445500D02*
X-834900D01*
G01X-835900D02*
Y-452500D01*
G01X-836900D02*
X-834900D01*
G01X-828600Y-449000D02*
X-826933D01*
Y-451100D01*
X-827433Y-451800D01*
X-828017Y-452267D01*
X-828850Y-452500D01*
X-829683Y-452267D01*
X-830267Y-451800D01*
X-830767Y-451100D01*
X-831100Y-450283D01*
X-831267Y-449350D01*
Y-448533D01*
X-831100Y-447833D01*
X-830767Y-447017D01*
X-830267Y-446317D01*
X-829767Y-445850D01*
X-829100Y-445500D01*
X-828517D01*
X-827850Y-445733D01*
X-827350Y-446200D01*
G01X-824217Y-452500D02*
Y-445500D01*
X-820383Y-452500D01*
Y-445500D01*
G01X-813833Y-452500D02*
X-817167D01*
Y-445500D01*
X-813833D01*
G01X-815167Y-448883D02*
X-817167D01*
G01X-810367Y-452500D02*
Y-445500D01*
X-808283D01*
X-807617Y-445850D01*
X-807200Y-446317D01*
X-807033Y-447250D01*
X-807200Y-448183D01*
X-807700Y-448767D01*
X-808283Y-449117D01*
X-810367D01*
G01X-808283D02*
X-807033Y-452500D01*
G01X-642033Y-455000D02*
Y-448000D01*
X-640367D01*
X-639700Y-448350D01*
X-639200Y-448817D01*
X-638783Y-449517D01*
X-638450Y-450333D01*
X-638367Y-451500D01*
X-638450Y-452667D01*
X-638783Y-453483D01*
X-639200Y-454184D01*
X-639700Y-454650D01*
X-640367Y-455000D01*
X-642033D01*
G01X-635483D02*
X-633400Y-448000D01*
X-631317Y-455000D01*
G01X-632067Y-452550D02*
X-634733D01*
G01X-626600Y-448000D02*
Y-455000D01*
G01X-628517Y-448000D02*
X-624683D01*
G01X-618133Y-455000D02*
X-621467D01*
Y-448000D01*
X-618133D01*
G01X-619467Y-451383D02*
X-621467D01*
G54D31*
X-1003346Y-36375D03*
X-960039D03*
X-133268D03*
X-89961D03*
G54D13*
X-1646000Y-140700D03*
X-836000Y-172000D03*
Y500D03*
X-28500Y-169500D03*
Y500D03*
G54D22*
X-1327756Y-127795D03*
X-457677D03*
G54D41*
G01X-1020800Y-457700D02*
G02X-1020300Y-458200I0J-500D01*
G01Y-458400D01*
G02X-1020900Y-459000I-600J0D01*
G01X-1021300D01*
G01X-1021800Y-460500D02*
Y-457700D01*
X-1020600D01*
G01X-1018340Y-459100D02*
G03I-2660J0D01*
G01X-1020700D02*
X-1020200Y-460500D01*
G54D23*
X-1312008Y-149449D03*
X-441929D03*
G54D32*
X-806854Y-99635D03*
Y-83100D03*
X-785200Y-99635D03*
G54D14*
X-1649000Y-121500D03*
Y-105752D03*
Y-113626D03*
Y-97878D03*
X-1327756Y-175039D03*
Y-167165D03*
Y-159291D03*
Y-143543D03*
Y-135669D03*
X-1319882Y-175039D03*
Y-167165D03*
Y-159291D03*
Y-143543D03*
Y-135669D03*
Y-127795D03*
X-1296260Y-175039D03*
X-1304134D03*
X-1296260Y-167165D03*
X-1304134D03*
X-1296260Y-159291D03*
X-1304134D03*
X-1296260Y-143543D03*
X-1304134D03*
X-1296260Y-135669D03*
X-1304134D03*
X-1296260Y-127795D03*
X-1304134D03*
X-793728Y-161850D03*
Y-153976D03*
Y-138228D03*
Y-146102D03*
X-457677Y-175039D03*
Y-167165D03*
Y-159291D03*
Y-143543D03*
Y-135669D03*
X-449803Y-175039D03*
Y-167165D03*
Y-159291D03*
Y-143543D03*
Y-135669D03*
Y-127795D03*
X-426181Y-175039D03*
X-434055D03*
X-426181Y-167165D03*
X-434055D03*
X-426181Y-159291D03*
X-434055D03*
X-426181Y-143543D03*
X-434055D03*
X-426181Y-135669D03*
X-434055D03*
X-426181Y-127795D03*
X-434055D03*
G54D33*
G01X-1184000Y-502500D02*
Y-512500D01*
G01X-1186683Y-502500D02*
X-1181317D01*
G01X-1176833Y-512500D02*
Y-502500D01*
X-1173917D01*
X-1172983Y-503000D01*
X-1172400Y-503667D01*
X-1172167Y-505000D01*
X-1172400Y-506333D01*
X-1173100Y-507167D01*
X-1173917Y-507667D01*
X-1176833D01*
G01X-1173917D02*
X-1172167Y-512500D01*
G01X-1167917D02*
X-1165000Y-502500D01*
X-1162083Y-512500D01*
G01X-1163133Y-509000D02*
X-1166867D01*
G01X-1155500Y-512500D02*
Y-508000D01*
X-1157833Y-502500D01*
G01X-1153167D02*
X-1155500Y-508000D01*
G01X-1135567Y-507167D02*
X-1135100Y-506667D01*
X-1134750Y-505834D01*
X-1134517Y-504667D01*
X-1134750Y-503667D01*
X-1135217Y-503000D01*
X-1136033Y-502500D01*
X-1139183D01*
Y-512500D01*
X-1135333D01*
X-1134517Y-511833D01*
X-1134050Y-510833D01*
X-1133817Y-509667D01*
X-1134050Y-508500D01*
X-1134750Y-507500D01*
X-1135567Y-507167D01*
X-1139183D01*
G01X-1129917Y-512500D02*
X-1127000Y-502500D01*
X-1124083Y-512500D01*
G01X-1125133Y-509000D02*
X-1128867D01*
G01X-1114933Y-503333D02*
X-1115633Y-502833D01*
X-1116450Y-502500D01*
X-1117383D01*
X-1118433Y-503000D01*
X-1119250Y-503833D01*
X-1119833Y-504833D01*
X-1120300Y-506500D01*
X-1120417Y-508000D01*
X-1120183Y-509500D01*
X-1119833Y-510500D01*
X-1119133Y-511500D01*
X-1118317Y-512167D01*
X-1117500Y-512500D01*
X-1116683D01*
X-1115867Y-512167D01*
X-1115167Y-511667D01*
X-1114583Y-511000D01*
G01X-1110567Y-512500D02*
Y-502500D01*
G01X-1106133D02*
X-1110567Y-508667D01*
G01X-1105433Y-512500D02*
X-1108583Y-505834D01*
G01X-1100833Y-512500D02*
Y-502500D01*
X-1098033D01*
X-1097100Y-503000D01*
X-1096400Y-504167D01*
X-1096167Y-505500D01*
X-1096400Y-506833D01*
X-1096983Y-507833D01*
X-1098033Y-508334D01*
X-1100833D01*
G01X-1091333Y-502500D02*
Y-512500D01*
X-1086667D01*
G01X-1082417D02*
X-1079500Y-502500D01*
X-1076583Y-512500D01*
G01X-1077633Y-509000D02*
X-1081367D01*
G01X-1072683Y-512500D02*
Y-502500D01*
X-1067317Y-512500D01*
Y-502500D01*
G01X-1058167Y-512500D02*
X-1062833D01*
Y-502500D01*
X-1058167D01*
G01X-1060033Y-507333D02*
X-1062833D01*
G01X-1043717Y-512500D02*
Y-502500D01*
X-1039283D01*
G01X-1040917Y-507333D02*
X-1043717D01*
G01X-1034917Y-512500D02*
X-1032000Y-502500D01*
X-1029083Y-512500D01*
G01X-1030133Y-509000D02*
X-1033867D01*
G01X-1021567Y-507167D02*
X-1021100Y-506667D01*
X-1020750Y-505834D01*
X-1020517Y-504667D01*
X-1020750Y-503667D01*
X-1021217Y-503000D01*
X-1022033Y-502500D01*
X-1025183D01*
Y-512500D01*
X-1021333D01*
X-1020517Y-511833D01*
X-1020050Y-510833D01*
X-1019817Y-509667D01*
X-1020050Y-508500D01*
X-1020750Y-507500D01*
X-1021567Y-507167D01*
X-1025183D01*
G01X-1002567D02*
X-1002100Y-506667D01*
X-1001750Y-505834D01*
X-1001517Y-504667D01*
X-1001750Y-503667D01*
X-1002217Y-503000D01*
X-1003033Y-502500D01*
X-1006183D01*
Y-512500D01*
X-1002333D01*
X-1001517Y-511833D01*
X-1001050Y-510833D01*
X-1000817Y-509667D01*
X-1001050Y-508500D01*
X-1001750Y-507500D01*
X-1002567Y-507167D01*
X-1006183D01*
G01X-985083Y-515833D02*
X-986250Y-514167D01*
X-986833Y-512500D01*
Y-505834D01*
X-986250Y-504167D01*
X-985083Y-502500D01*
G01X-975000Y-512500D02*
X-975933Y-512333D01*
X-976750Y-511667D01*
X-977450Y-510667D01*
X-977917Y-509500D01*
X-978150Y-508167D01*
Y-506833D01*
X-977917Y-505500D01*
X-977450Y-504333D01*
X-976750Y-503333D01*
X-975933Y-502667D01*
X-975000Y-502500D01*
X-974067Y-502667D01*
X-973250Y-503333D01*
X-972550Y-504333D01*
X-972083Y-505500D01*
X-971850Y-506833D01*
Y-508167D01*
X-972083Y-509500D01*
X-972550Y-510667D01*
X-973250Y-511667D01*
X-974067Y-512333D01*
X-975000Y-512500D01*
G01X-967950Y-511167D02*
X-967017Y-512000D01*
X-965967Y-512500D01*
X-965033D01*
X-964100Y-512000D01*
X-963400Y-511167D01*
X-963050Y-510000D01*
X-963283Y-508834D01*
X-963867Y-507833D01*
X-964917Y-507167D01*
X-966317Y-506833D01*
X-967133Y-506167D01*
X-967483Y-505000D01*
X-967250Y-503833D01*
X-966667Y-503000D01*
X-965850Y-502500D01*
X-965033D01*
X-964217Y-502833D01*
X-963517Y-503667D01*
G01X-958333Y-512500D02*
Y-502500D01*
X-955533D01*
X-954600Y-503000D01*
X-953900Y-504167D01*
X-953667Y-505500D01*
X-953900Y-506833D01*
X-954483Y-507833D01*
X-955533Y-508334D01*
X-958333D01*
G01X-945917Y-515833D02*
X-944750Y-514167D01*
X-944167Y-512500D01*
Y-505834D01*
X-944750Y-504167D01*
X-945917Y-502500D01*
G01X-902000Y-470000D02*
Y-460000D01*
X-903400Y-462000D01*
G01Y-470000D02*
X-900600D01*
G01X-892500Y-470333D02*
X-892733Y-470167D01*
Y-469833D01*
X-892500Y-469667D01*
X-892267Y-469833D01*
Y-470167D01*
X-892500Y-470333D01*
G01Y-465834D02*
X-892733Y-465667D01*
Y-465333D01*
X-892500Y-465167D01*
X-892267Y-465333D01*
Y-465667D01*
X-892500Y-465834D01*
G01X-883000Y-470000D02*
Y-460000D01*
X-884400Y-462000D01*
G01Y-470000D02*
X-881600D01*
G01X-785060Y-472187D02*
X-784127Y-473020D01*
X-783077Y-473520D01*
X-782143D01*
X-781210Y-473020D01*
X-780510Y-472187D01*
X-780160Y-471020D01*
X-780393Y-469854D01*
X-780977Y-468853D01*
X-782027Y-468187D01*
X-783427Y-467853D01*
X-784243Y-467187D01*
X-784593Y-466020D01*
X-784360Y-464853D01*
X-783777Y-464020D01*
X-782960Y-463520D01*
X-782143D01*
X-781327Y-463853D01*
X-780627Y-464687D01*
G01X-775560Y-473520D02*
Y-463520D01*
G01X-770660D02*
Y-473520D01*
G01Y-468520D02*
X-775560D01*
G01X-766527Y-473520D02*
X-763610Y-463520D01*
X-760693Y-473520D01*
G01X-761743Y-470020D02*
X-765477D01*
G01X-757610Y-463520D02*
X-755977Y-473520D01*
X-754110Y-463520D01*
X-752243Y-473520D01*
X-750610Y-463520D01*
G01X-668067Y-470500D02*
X-667367Y-471667D01*
X-666433Y-472333D01*
X-665383Y-472500D01*
X-664450Y-472333D01*
X-663517Y-471500D01*
X-662933Y-470500D01*
X-662817Y-469500D01*
X-663050Y-468334D01*
X-663867Y-467500D01*
X-664683Y-467167D01*
X-665733D01*
G01X-664683D02*
X-663983Y-466667D01*
X-663400Y-465834D01*
X-663167Y-464833D01*
X-663400Y-463833D01*
X-663983Y-463000D01*
X-665033Y-462500D01*
X-666083Y-462667D01*
X-667133Y-463333D01*
G01X-656000Y-462500D02*
X-656933Y-462833D01*
X-657633Y-463667D01*
X-658100Y-464667D01*
X-658450Y-466000D01*
X-658567Y-467500D01*
X-658450Y-469000D01*
X-658100Y-470333D01*
X-657633Y-471334D01*
X-656933Y-472167D01*
X-656000Y-472500D01*
X-655067Y-472167D01*
X-654367Y-471334D01*
X-653900Y-470333D01*
X-653550Y-469000D01*
X-653433Y-467500D01*
X-653550Y-466000D01*
X-653900Y-464667D01*
X-654367Y-463667D01*
X-655067Y-462833D01*
X-656000Y-462500D01*
G01X-648017Y-469167D02*
X-644983D01*
G01X-639917Y-472500D02*
X-637000Y-462500D01*
X-634083Y-472500D01*
G01X-635133Y-469000D02*
X-638867D01*
G01X-629833Y-472500D02*
Y-462500D01*
X-627033D01*
X-626100Y-463000D01*
X-625400Y-464167D01*
X-625167Y-465500D01*
X-625400Y-466833D01*
X-625983Y-467833D01*
X-627033Y-468334D01*
X-629833D01*
G01X-620333Y-472500D02*
Y-462500D01*
X-617417D01*
X-616483Y-463000D01*
X-615900Y-463667D01*
X-615667Y-465000D01*
X-615900Y-466333D01*
X-616600Y-467167D01*
X-617417Y-467667D01*
X-620333D01*
G01X-617417D02*
X-615667Y-472500D01*
G01X-610017Y-469167D02*
X-606983D01*
G01X-599000Y-472500D02*
Y-462500D01*
X-600400Y-464500D01*
G01Y-472500D02*
X-597600D01*
G01X-588100D02*
Y-462500D01*
X-592417Y-469667D01*
X-586583D01*
G54D24*
X-1282480Y-172283D03*
Y-130157D03*
Y-94724D03*
Y-59291D03*
Y-23858D03*
X-1253740Y-184094D03*
X-1225394D03*
X-1207677Y-154567D03*
Y-112441D03*
Y-77008D03*
Y-41575D03*
Y-6142D03*
X-412402Y-172283D03*
Y-130157D03*
Y-94724D03*
Y-59291D03*
Y-23858D03*
X-383661Y-184094D03*
X-355315D03*
X-337598Y-154567D03*
Y-112441D03*
Y-77008D03*
Y-41575D03*
Y-6142D03*
G54D15*
X-1654488Y7244D03*
X-1649488D03*
X-1644488D03*
X-1639488D03*
X-1634488D03*
X-1629488D03*
G54D34*
G01X-1174900Y-473500D02*
X-1171300Y-466100D01*
X-1171800Y-465700D01*
X-1175900Y-473200D01*
X-1176200Y-471200D01*
X-1172500Y-465400D01*
X-1175700Y-471300D01*
X-1176500Y-469800D01*
X-1172900Y-464900D01*
X-1173600Y-451800D01*
X-1173700Y-449900D01*
X-1182100D01*
X-1187400Y-473000D01*
X-1182400D01*
X-1177800Y-456000D01*
X-1177000Y-455900D01*
X-1176100Y-468500D01*
X-1173700Y-464500D01*
X-1174600Y-450800D01*
X-1181500Y-450900D01*
X-1186400Y-472100D01*
X-1183100D01*
X-1178300Y-454800D01*
X-1176600Y-455000D01*
X-1175500Y-466300D01*
X-1174600Y-464300D01*
X-1175400Y-451700D01*
X-1181000Y-451800D01*
X-1185300Y-471300D01*
X-1183800Y-471400D01*
X-1179000Y-454300D01*
X-1176200D01*
X-1175200Y-462200D01*
X-1176200Y-452500D01*
X-1180500Y-452800D01*
X-1184300Y-470600D01*
X-1179700Y-453400D01*
X-1176800D01*
G01X-1182820Y-448900D02*
X-1188360Y-473900D01*
X-1181580D01*
X-1177300Y-456700D01*
X-1176920Y-473900D01*
X-1172260D01*
X-1163400Y-456920D01*
X-1167240Y-473900D01*
X-1160380D01*
X-1154840Y-448900D01*
X-1164540D01*
X-1172540Y-464820D01*
X-1172880Y-448900D01*
X-1182820D01*
G01X-1155800Y-449500D02*
X-1161100Y-472900D01*
X-1166100Y-473000D01*
X-1166000Y-471900D01*
X-1161800Y-472100D01*
X-1161300Y-471000D01*
X-1165900Y-471100D01*
X-1165700Y-470000D01*
X-1161300D01*
X-1160800Y-469200D01*
X-1165300Y-469100D01*
X-1165200Y-468100D01*
X-1160700D01*
X-1160400Y-467100D01*
X-1165100Y-467200D01*
X-1164900Y-466300D01*
X-1160300Y-466200D01*
X-1160000Y-465200D01*
X-1164700Y-465300D01*
X-1164400Y-464200D01*
X-1159700Y-464300D01*
X-1159300Y-463100D01*
X-1164700Y-463500D01*
X-1164000Y-462500D01*
X-1159500Y-462600D01*
X-1159000Y-461700D01*
X-1163900D01*
X-1163600Y-460600D01*
X-1159100Y-460800D01*
X-1158800Y-459900D01*
X-1163200D01*
X-1163100Y-459200D01*
X-1158800D01*
X-1158300Y-458500D01*
X-1163000Y-458400D01*
X-1162900Y-457800D01*
X-1158400Y-457900D01*
X-1158200Y-457200D01*
X-1162500Y-457000D01*
X-1163100Y-456500D01*
X-1157800D01*
X-1157500Y-455500D01*
X-1156600Y-449800D01*
X-1164000D01*
X-1164500Y-450700D01*
X-1157600D01*
X-1157800Y-451700D01*
X-1165000Y-451600D01*
X-1165400Y-452400D01*
X-1157900Y-452500D01*
X-1157800Y-453500D01*
X-1165900Y-453200D01*
X-1166200Y-453900D01*
X-1158000Y-454300D01*
X-1158300Y-455300D01*
X-1166600Y-454800D01*
X-1158900Y-455900D01*
X-1167000Y-455600D01*
X-1163500Y-456400D01*
X-1167300Y-456300D01*
X-1171700Y-465200D01*
X-1169200Y-466400D01*
X-1164500Y-457200D01*
X-1166900Y-457100D01*
X-1170600Y-465200D01*
X-1169500Y-465500D01*
X-1166000Y-457800D01*
G01X-1170300Y-466300D02*
X-1174000Y-473600D01*
G01X-1169500Y-466900D02*
X-1172800Y-473000D01*
G01X-1152800Y-456400D02*
X-1156600Y-473100D01*
X-1152200Y-473000D01*
X-1148300Y-456600D01*
X-1149500D01*
X-1152900Y-472000D01*
X-1155600Y-472300D01*
X-1152100Y-456500D01*
X-1150400Y-456400D01*
X-1153600Y-471200D01*
X-1154500Y-471400D01*
X-1151400Y-457200D01*
G01X-1153420Y-455700D02*
X-1157540Y-473900D01*
X-1151380D01*
X-1147440Y-455700D01*
X-1153420D01*
G01X-1151600Y-450100D02*
X-1146700Y-450000D01*
X-1147000Y-451000D01*
X-1151700D01*
G01X-1152020Y-448900D02*
X-1152660Y-451900D01*
X-1146380D01*
X-1145740Y-448900D01*
X-1152020D01*
G01X-1129400Y-468900D02*
X-1131800Y-471900D01*
X-1136500Y-473700D01*
X-1142100Y-473600D01*
X-1144600Y-472300D01*
X-1145800Y-471000D01*
X-1146400Y-469500D01*
X-1146700Y-467600D01*
X-1146500Y-464600D01*
X-1145400Y-461200D01*
X-1143500Y-459100D01*
X-1140200Y-456900D01*
X-1136100Y-456200D01*
X-1132300Y-456400D01*
X-1129400Y-457900D01*
X-1127500Y-460900D01*
X-1132500Y-461000D01*
X-1133400Y-459200D01*
X-1135100Y-458100D01*
X-1136800Y-458000D01*
X-1138600Y-458900D01*
X-1140300Y-460700D01*
X-1141800Y-463600D01*
X-1142400Y-466600D01*
X-1141500Y-470400D01*
X-1140200Y-471500D01*
X-1138300Y-471600D01*
X-1136300Y-471400D01*
X-1134500Y-469100D01*
X-1130300Y-469000D01*
X-1132500Y-471200D01*
X-1134900Y-472000D01*
X-1137200Y-472800D01*
X-1142300Y-472700D01*
X-1144900Y-470600D01*
X-1145800Y-467400D01*
X-1145500Y-465100D01*
X-1144700Y-462000D01*
X-1143300Y-460200D01*
X-1139800Y-457700D01*
X-1135400Y-457000D01*
X-1131300Y-457600D01*
X-1128800Y-460100D01*
X-1132100D01*
X-1134300Y-457900D01*
X-1130100Y-458800D01*
X-1129500Y-459400D01*
X-1132600Y-459000D01*
G01X-1133300Y-461900D02*
Y-461420D01*
X-1133640Y-460240D01*
X-1134300Y-459200D01*
X-1135200Y-458900D01*
X-1136580D01*
X-1138060Y-459820D01*
X-1139360Y-461000D01*
X-1140240Y-462220D01*
X-1140880Y-463920D01*
X-1141300Y-465380D01*
X-1141500Y-467060D01*
Y-468020D01*
X-1141020Y-469220D01*
X-1139780Y-470700D01*
X-1137160D01*
X-1135840Y-469500D01*
X-1134980Y-468200D01*
X-1134940Y-468100D01*
X-1128180D01*
X-1128240Y-468240D01*
X-1128840Y-469340D01*
X-1129020Y-469800D01*
X-1129740Y-470700D01*
X-1130500Y-471460D01*
X-1131660Y-472420D01*
X-1132820Y-473200D01*
X-1133740Y-473740D01*
X-1136380Y-474500D01*
X-1141640D01*
X-1142540Y-474320D01*
X-1144220Y-473760D01*
X-1144900Y-473240D01*
X-1146240Y-471900D01*
X-1146780Y-471180D01*
X-1146940Y-470880D01*
X-1147320Y-469660D01*
X-1147500Y-468640D01*
Y-464780D01*
X-1146940Y-462540D01*
X-1146380Y-461580D01*
X-1145980Y-460780D01*
X-1145420Y-459880D01*
X-1143700Y-458140D01*
X-1142740Y-457380D01*
X-1142000Y-456820D01*
X-1140240Y-456040D01*
X-1139500Y-455660D01*
X-1138800Y-455480D01*
X-1137260Y-455300D01*
X-1134320D01*
X-1132020Y-455500D01*
X-1130940Y-455860D01*
X-1130580Y-456020D01*
X-1129260Y-456780D01*
X-1128940Y-457100D01*
X-1127820Y-458420D01*
X-1127060Y-460300D01*
X-1126900Y-460800D01*
Y-461900D01*
X-1133300D01*
G01X-1137900Y-458000D02*
X-1140300Y-459100D01*
X-1142500Y-460900D01*
X-1143900Y-462600D01*
X-1144800Y-467600D01*
X-1144200Y-470000D01*
X-1141000Y-472300D01*
X-1136400Y-472200D01*
X-1131600Y-469600D01*
X-1135400Y-470400D01*
X-1141100Y-471400D01*
X-1142100Y-470700D01*
X-1142700Y-469000D01*
X-1143100Y-467100D01*
X-1142700Y-464100D01*
X-1140500Y-459900D01*
X-1143400Y-463700D01*
X-1143600Y-465700D01*
X-1143900Y-467700D01*
X-1143000Y-469900D01*
G01X-1113500Y-459200D02*
X-1123500Y-459300D01*
X-1123700Y-460100D01*
X-1114300Y-460000D01*
X-1116500Y-460800D01*
X-1124200Y-461000D01*
X-1124400Y-461900D01*
X-1117600Y-461800D01*
X-1118800Y-462800D01*
X-1124500Y-462700D01*
X-1124600Y-463600D01*
X-1119300Y-463700D01*
X-1120100Y-464800D01*
X-1125000Y-464600D01*
Y-465500D01*
X-1120600Y-465700D01*
X-1120800Y-466700D01*
X-1125300Y-466500D01*
X-1125500Y-467400D01*
X-1121000Y-467600D01*
X-1121200Y-468700D01*
X-1125600Y-468400D01*
X-1125900Y-469100D01*
X-1121500Y-469500D01*
X-1121700Y-470700D01*
X-1126100Y-470000D01*
X-1126200Y-470700D01*
X-1121900Y-471200D01*
X-1122100Y-472000D01*
X-1126300Y-471700D01*
X-1126700Y-472300D01*
X-1122100Y-472700D01*
X-1122200Y-473100D01*
X-1126800Y-473200D01*
G01X-1114060Y-460760D02*
X-1114840Y-460920D01*
X-1115740Y-461140D01*
X-1116880Y-461820D01*
X-1117700Y-462640D01*
X-1118620Y-463340D01*
X-1118840Y-464020D01*
X-1119440Y-464820D01*
X-1119660Y-465480D01*
X-1120060Y-466280D01*
X-1120280Y-466960D01*
X-1120480Y-468360D01*
X-1120680Y-468940D01*
X-1120880Y-469940D01*
X-1121080Y-470540D01*
X-1121700Y-472980D01*
X-1121820Y-473900D01*
X-1127640D01*
X-1126920Y-471060D01*
X-1126720Y-470440D01*
X-1126500Y-468800D01*
X-1126320Y-467860D01*
X-1126120Y-467260D01*
X-1125920Y-466260D01*
X-1125720Y-465660D01*
X-1125300Y-464000D01*
X-1125120Y-462220D01*
X-1124920Y-461660D01*
X-1124720Y-460660D01*
X-1124520Y-460060D01*
X-1123720Y-456800D01*
X-1123580Y-455700D01*
X-1117880D01*
X-1118100Y-456160D01*
Y-458740D01*
X-1116500Y-457160D01*
X-1115780Y-456620D01*
X-1114680Y-456060D01*
X-1113560Y-455680D01*
X-1112460Y-455500D01*
X-1111720D01*
X-1112460Y-458440D01*
X-1114060Y-460760D01*
G01X-1123100Y-456500D02*
X-1118900Y-456600D01*
X-1118800Y-457600D01*
X-1123100Y-457500D01*
X-1123300Y-458500D01*
X-1113100Y-458400D01*
X-1112600Y-456400D01*
X-1116100Y-457600D01*
X-1113500D01*
G01X-1105100Y-471100D02*
X-1104060D01*
X-1103780Y-470820D01*
X-1103200Y-470640D01*
X-1102080Y-469740D01*
X-1100800Y-468240D01*
X-1100380Y-467400D01*
X-1100180Y-467100D01*
X-1099960Y-466660D01*
X-1099540Y-465720D01*
X-1099320Y-465060D01*
X-1099100Y-464180D01*
Y-461220D01*
X-1099360Y-460200D01*
X-1099660Y-459900D01*
X-1100700Y-458640D01*
X-1101220Y-458300D01*
X-1103340D01*
X-1103700Y-458640D01*
X-1105300Y-459840D01*
X-1105760Y-460320D01*
X-1106180Y-460940D01*
X-1107060Y-462020D01*
X-1107260Y-462880D01*
X-1107660Y-463660D01*
X-1108100Y-465000D01*
Y-468640D01*
X-1107620Y-469600D01*
X-1107140Y-470340D01*
X-1105980Y-471100D01*
X-1105100D01*
G01X-1112540Y-460460D02*
X-1110680Y-458140D01*
X-1109940Y-457580D01*
X-1109000Y-456840D01*
X-1108480Y-456660D01*
X-1107940Y-456400D01*
X-1107740Y-456200D01*
X-1107480Y-456060D01*
X-1106880Y-455860D01*
X-1106480Y-455660D01*
X-1105960Y-455480D01*
X-1104600Y-455300D01*
X-1103440Y-455100D01*
X-1100940D01*
X-1098240Y-455480D01*
X-1097720Y-455660D01*
X-1097020Y-456020D01*
X-1096180Y-456640D01*
X-1095620Y-456820D01*
X-1095540Y-456900D01*
X-1094200Y-458440D01*
X-1093660Y-459520D01*
X-1093460Y-460100D01*
X-1093100Y-461020D01*
Y-464400D01*
X-1093420Y-465360D01*
X-1094300Y-465520D01*
X-1094720Y-465740D01*
X-1095320Y-465940D01*
X-1096120Y-466340D01*
X-1096720Y-466540D01*
X-1097100Y-466720D01*
X-1098100Y-466920D01*
X-1098520Y-467140D01*
X-1099160Y-467360D01*
X-1101180Y-468700D01*
X-1094660D01*
X-1095220Y-469800D01*
X-1095560Y-470320D01*
X-1097480Y-472220D01*
X-1099940Y-473740D01*
X-1102580Y-474500D01*
X-1108800D01*
X-1109300Y-474340D01*
X-1111220Y-473560D01*
X-1111720Y-473240D01*
X-1113240Y-471720D01*
X-1113560Y-471240D01*
X-1113760Y-470660D01*
X-1114140Y-469980D01*
X-1114320Y-469120D01*
X-1114500Y-468680D01*
Y-464980D01*
X-1114320Y-464260D01*
X-1114140Y-463720D01*
X-1113940Y-463320D01*
X-1113720Y-462660D01*
X-1113560Y-462000D01*
X-1111880Y-460320D01*
X-1112540Y-460460D01*
G01X-1099300Y-466400D02*
X-1093800Y-464400D01*
X-1093900Y-461100D01*
X-1094800Y-459000D01*
X-1096800Y-457300D01*
X-1100000Y-456100D01*
X-1102800Y-455900D01*
X-1106300Y-456300D01*
X-1109600Y-458100D01*
X-1111400Y-460500D01*
X-1112900Y-462600D01*
X-1113600Y-465600D01*
X-1113500Y-469100D01*
X-1112100Y-471900D01*
X-1109600Y-473300D01*
X-1105700Y-473800D01*
X-1101000Y-473400D01*
X-1098200Y-471800D01*
X-1096600Y-470100D01*
X-1096000Y-469500D01*
X-1100800Y-469700D01*
X-1102300Y-471100D01*
X-1097900Y-470400D01*
X-1100300Y-471800D01*
X-1103200Y-471400D01*
X-1100600Y-472600D01*
X-1103000D01*
X-1103700Y-471900D01*
X-1103400Y-473000D01*
X-1104600Y-471900D01*
X-1106200D01*
X-1104100Y-473100D01*
X-1107200Y-472700D01*
X-1110100Y-472100D01*
X-1111500Y-470900D01*
X-1112600Y-468600D01*
X-1112700Y-466000D01*
X-1112400Y-463700D01*
X-1111400Y-461600D01*
X-1109600Y-459500D01*
X-1108100Y-458200D01*
X-1105900Y-457200D01*
X-1102200Y-456700D01*
X-1099600Y-457300D01*
X-1097000Y-458400D01*
X-1095500Y-459500D01*
X-1094600Y-461900D01*
X-1094500Y-463900D01*
X-1098800Y-465200D01*
X-1098600Y-464000D01*
X-1095100Y-463100D01*
X-1095300Y-462000D01*
X-1098500Y-463000D01*
X-1098600Y-461700D01*
X-1095600Y-461300D01*
X-1095900Y-460200D01*
X-1098400Y-460700D01*
X-1098900Y-459900D01*
X-1096600Y-459400D01*
X-1097100Y-458900D01*
X-1099400Y-459000D01*
X-1098800Y-458500D01*
X-1100600Y-458000D01*
X-1102400Y-457400D01*
X-1104200Y-457500D01*
X-1106200Y-458100D01*
X-1107900Y-459000D01*
X-1110500Y-462200D01*
X-1111800Y-464800D01*
Y-467700D01*
X-1110700Y-470300D01*
X-1108700Y-472000D01*
X-1106600Y-471900D01*
X-1107900Y-470300D01*
X-1108900Y-468700D01*
Y-465500D01*
X-1107900Y-462300D01*
X-1106500Y-459900D01*
X-1104100Y-458200D01*
X-1108000Y-460000D01*
X-1108100Y-461500D01*
X-1108700Y-461200D01*
X-1110300Y-463600D01*
X-1111000Y-466000D01*
X-1110700Y-468100D01*
X-1109500Y-470600D01*
X-1107700Y-471400D01*
X-1109300Y-469100D01*
X-1109800Y-467600D01*
X-1108600Y-462200D01*
X-1110400Y-466800D01*
G01X-1113600Y-460900D02*
X-1112100Y-459000D01*
G01X-1093100Y-469400D02*
X-1087900Y-469700D01*
X-1086500Y-471400D01*
X-1083400Y-472300D01*
X-1081000Y-472000D01*
X-1079300Y-470600D01*
X-1079000Y-468900D01*
X-1079500Y-467700D01*
X-1080300Y-466600D01*
X-1081800Y-466000D01*
X-1083300Y-465500D01*
X-1085300Y-465000D01*
X-1087900Y-464000D01*
X-1089100Y-463200D01*
X-1089800Y-461000D01*
X-1089500Y-459000D01*
X-1088600Y-457700D01*
X-1086500Y-456700D01*
X-1084600Y-456100D01*
X-1081900Y-455900D01*
X-1079900Y-455800D01*
X-1076900Y-456300D01*
X-1075000Y-457000D01*
X-1073700Y-458000D01*
X-1073300Y-459400D01*
X-1077600Y-459500D01*
X-1078100Y-458800D01*
X-1074300Y-458500D01*
X-1074600Y-457800D01*
X-1078200Y-458200D01*
X-1076000Y-457400D01*
X-1079100Y-457700D01*
X-1077100Y-456900D01*
X-1080100Y-457300D01*
X-1079200Y-456600D01*
X-1083100Y-456800D01*
X-1080600Y-457300D01*
X-1083400Y-457700D01*
X-1083600Y-457000D01*
X-1087900Y-458400D01*
X-1084000Y-458100D01*
X-1088600Y-459100D01*
X-1088800Y-461500D01*
X-1087700Y-463600D01*
X-1084400Y-464300D01*
X-1081200Y-465400D01*
X-1078800Y-467300D01*
X-1078300Y-470500D01*
X-1079900Y-472600D01*
X-1083500Y-473300D01*
X-1085600Y-472600D01*
X-1088800Y-470500D01*
X-1092600Y-470200D01*
X-1092100Y-471800D01*
X-1091700Y-471300D01*
X-1089300Y-471500D01*
X-1091300Y-472300D01*
X-1088700Y-471600D01*
X-1084000Y-473500D01*
X-1089100D01*
X-1091000Y-472900D01*
X-1087200Y-472800D01*
X-1082700Y-473700D01*
X-1079000Y-473600D01*
X-1076500Y-472300D01*
X-1074700Y-470600D01*
X-1074300Y-467300D01*
X-1074800Y-465300D01*
X-1078800Y-463600D01*
X-1081600Y-462900D01*
X-1083400Y-462500D01*
X-1084800Y-461500D01*
X-1085000Y-458900D01*
X-1088100Y-459800D01*
X-1087200Y-462700D01*
X-1085000Y-463400D01*
X-1082000Y-464100D01*
X-1079600Y-465100D01*
X-1078200Y-466500D01*
X-1077700Y-468500D01*
X-1077500Y-470100D01*
X-1079200Y-472800D01*
X-1076800Y-471400D01*
X-1075300Y-470000D01*
X-1077300Y-470900D01*
X-1075000Y-468800D01*
X-1075200Y-466100D01*
X-1082700Y-462700D01*
X-1084200Y-462900D01*
X-1086600Y-461800D01*
X-1087200Y-460300D01*
X-1085800Y-459800D01*
X-1086600Y-461000D01*
X-1085300Y-460400D01*
X-1085600Y-461400D01*
X-1076700Y-466500D01*
X-1075900Y-467100D01*
X-1075700Y-468400D01*
X-1076800Y-469500D01*
X-1077800Y-466200D01*
X-1075900Y-468800D01*
G01X-1093780Y-468700D02*
X-1087100D01*
Y-469740D01*
X-1086800Y-470060D01*
X-1086520Y-470600D01*
X-1085820Y-470820D01*
X-1085660Y-471000D01*
X-1085120Y-471260D01*
X-1084400Y-471500D01*
X-1082360D01*
X-1080540Y-470600D01*
X-1080100Y-470140D01*
Y-469780D01*
X-1079840Y-469380D01*
X-1080380Y-467740D01*
X-1081440Y-466940D01*
X-1082560Y-466720D01*
X-1085740Y-465920D01*
X-1086940Y-465520D01*
X-1087600Y-465360D01*
X-1087740Y-465200D01*
X-1088540Y-464800D01*
X-1089140Y-464200D01*
X-1089540Y-464000D01*
X-1089800Y-463740D01*
X-1090000Y-463340D01*
X-1090180Y-463180D01*
X-1090500Y-462200D01*
Y-459800D01*
X-1090320Y-459260D01*
X-1090140Y-458500D01*
X-1090000Y-458260D01*
X-1089000Y-457260D01*
X-1088860Y-456940D01*
X-1085920Y-455480D01*
X-1083620Y-455100D01*
X-1082060Y-454900D01*
X-1080520D01*
X-1078580Y-455100D01*
X-1076240Y-455480D01*
X-1075120Y-455860D01*
X-1074800Y-456020D01*
X-1073680Y-456760D01*
X-1073160Y-457300D01*
X-1072620Y-458020D01*
X-1072500Y-458240D01*
Y-460300D01*
X-1078500D01*
Y-459200D01*
X-1079580Y-458380D01*
X-1080160Y-458100D01*
X-1082380D01*
X-1083280Y-458360D01*
X-1084020Y-458940D01*
X-1084340Y-459900D01*
X-1084060Y-460720D01*
X-1083740Y-461340D01*
X-1081860Y-462280D01*
X-1079400Y-462500D01*
X-1078660Y-462680D01*
X-1078100Y-462860D01*
X-1076500Y-463460D01*
X-1075320Y-463860D01*
X-1075060Y-464000D01*
X-1073820Y-465220D01*
X-1073480Y-466260D01*
X-1073300Y-467160D01*
Y-468420D01*
X-1073860Y-470700D01*
X-1074000Y-470960D01*
X-1075140Y-472300D01*
X-1075280Y-472440D01*
X-1076600Y-473380D01*
X-1077320Y-473740D01*
X-1079600Y-474500D01*
X-1088240D01*
X-1089160Y-474320D01*
X-1089920Y-474120D01*
X-1090860Y-473760D01*
X-1091560Y-473400D01*
X-1092700Y-472460D01*
X-1093180Y-471980D01*
X-1093340Y-471480D01*
X-1093520Y-471100D01*
X-1093700Y-470320D01*
X-1093780Y-468700D01*
G01X-1095100D02*
X-1092800D01*
G01X-1058300Y-469400D02*
X-1055400Y-467100D01*
X-1053900Y-463700D01*
X-1054400Y-461200D01*
X-1055900Y-459900D01*
X-1054800Y-463500D01*
X-1055400Y-463600D01*
X-1054600Y-464500D01*
X-1055700D01*
X-1055400Y-465300D01*
X-1056200Y-466800D01*
G01X-1059300Y-457700D02*
X-1059100Y-455600D01*
X-1055200Y-456300D01*
X-1052700Y-457900D01*
X-1051100Y-460800D01*
X-1050900Y-465200D01*
X-1052900Y-469400D01*
X-1055300Y-471900D01*
X-1059000Y-473500D01*
X-1066000D01*
X-1068000Y-471900D01*
X-1070200Y-468700D01*
X-1070600Y-464500D01*
X-1069000Y-460500D01*
X-1066000Y-457500D01*
X-1063000Y-456500D01*
X-1059200Y-456000D01*
X-1053000Y-458500D01*
X-1052000Y-461500D01*
Y-465700D01*
X-1053400Y-468600D01*
X-1055700Y-471000D01*
X-1058900Y-472600D01*
X-1063700Y-473000D01*
X-1065900Y-473600D01*
X-1068300Y-472900D01*
X-1070600Y-469300D01*
X-1065100Y-472600D01*
X-1060800Y-472200D01*
X-1057200Y-470700D01*
X-1055200Y-469100D01*
X-1053300Y-466500D01*
X-1052500Y-463400D01*
X-1052900Y-460100D01*
X-1057000Y-457400D01*
X-1058700Y-457200D01*
X-1057000Y-458500D01*
X-1055100Y-459800D01*
X-1053800Y-460900D01*
X-1053400Y-463100D01*
X-1053600Y-465600D01*
X-1054800Y-467500D01*
X-1056400Y-469200D01*
X-1058500Y-470200D01*
X-1060200Y-470700D01*
X-1061500Y-471400D01*
X-1063300Y-471600D01*
X-1065400Y-471500D01*
X-1069000Y-469300D01*
X-1069600Y-466400D01*
X-1069700Y-463700D01*
X-1068600Y-461200D01*
X-1066700Y-459200D01*
X-1063900Y-457600D01*
X-1061100Y-457000D01*
X-1059600D01*
X-1060200Y-457500D01*
X-1063300Y-458000D01*
X-1065300Y-459500D01*
X-1066900Y-460600D01*
X-1067900Y-462100D01*
X-1068800Y-464300D01*
X-1068700Y-466900D01*
X-1068200Y-469100D01*
X-1066900Y-470200D01*
X-1064300Y-470900D01*
X-1065700Y-469300D01*
X-1065800Y-465900D01*
X-1065300Y-462900D01*
X-1061200Y-458200D01*
X-1063600Y-458900D01*
X-1066400Y-461300D01*
X-1067800Y-464200D01*
Y-467200D01*
X-1067400Y-469300D01*
X-1066300Y-469700D01*
X-1067100Y-466400D01*
X-1066600Y-463400D01*
X-1064700Y-460000D01*
X-1062600Y-458800D01*
X-1065300Y-461700D01*
X-1066700Y-467400D01*
G01X-1060840Y-455100D02*
X-1057160D01*
X-1055260Y-455480D01*
X-1054740Y-455640D01*
X-1053380Y-456420D01*
X-1052660Y-456800D01*
X-1052020Y-457420D01*
X-1051820Y-458020D01*
X-1051200Y-458660D01*
X-1051000Y-459060D01*
X-1050840Y-459200D01*
X-1050700Y-459780D01*
Y-460140D01*
X-1050400Y-460460D01*
X-1050280Y-460680D01*
X-1050100Y-461740D01*
Y-464240D01*
X-1050280Y-465160D01*
X-1050480Y-465980D01*
X-1050680Y-467120D01*
X-1051220Y-468180D01*
X-1051840Y-469020D01*
X-1052040Y-469600D01*
X-1052740Y-470500D01*
X-1054480Y-472240D01*
X-1055000Y-472580D01*
X-1055420Y-472780D01*
X-1056220Y-473380D01*
X-1056920Y-473740D01*
X-1059380Y-474500D01*
X-1065600D01*
X-1067860Y-473740D01*
X-1068160Y-473600D01*
X-1069500Y-472460D01*
X-1069820Y-472120D01*
X-1070380Y-471200D01*
X-1071140Y-469860D01*
X-1071300Y-469400D01*
Y-464580D01*
X-1071120Y-463880D01*
X-1070740Y-462900D01*
X-1070540Y-462320D01*
X-1069980Y-461000D01*
X-1068840Y-459500D01*
X-1066900Y-457560D01*
X-1066180Y-457020D01*
X-1065400Y-456620D01*
X-1064440Y-456040D01*
X-1063500Y-455660D01*
X-1062940Y-455480D01*
X-1060840Y-455100D01*
G01X-1057800Y-458580D02*
X-1057000Y-459120D01*
X-1056760Y-459840D01*
X-1056340Y-460460D01*
X-1056100Y-461640D01*
Y-463760D01*
X-1056320Y-464860D01*
X-1056720Y-466060D01*
X-1056940Y-466920D01*
X-1057200Y-467460D01*
X-1057640Y-467880D01*
X-1058040Y-468480D01*
X-1059960Y-470420D01*
X-1061020Y-470840D01*
X-1061420Y-471100D01*
X-1062720D01*
X-1063340Y-470840D01*
X-1063860Y-470600D01*
X-1064360Y-470080D01*
X-1064820Y-469400D01*
X-1065100Y-468840D01*
Y-464920D01*
X-1064880Y-464120D01*
X-1064420Y-462780D01*
X-1064160Y-462520D01*
X-1063620Y-461700D01*
X-1063200Y-460840D01*
X-1062500Y-460140D01*
X-1062120Y-459860D01*
X-1061720Y-459360D01*
X-1060600Y-458580D01*
X-1060040Y-458300D01*
X-1058360D01*
X-1057800Y-458580D01*
G01X-1040300Y-459100D02*
X-1041400Y-464800D01*
G01X-1044800Y-458200D02*
X-1041400D01*
X-1044300Y-472700D01*
X-1047400Y-472300D01*
X-1044100Y-458800D01*
X-1042400Y-459100D01*
X-1045100Y-471900D01*
X-1046500D01*
X-1043400Y-459700D01*
X-1045600Y-471500D01*
G01X-1036600Y-449900D02*
X-1036800Y-451300D01*
X-1038600Y-452400D01*
X-1039800Y-456100D01*
X-1033700Y-456500D01*
X-1032300Y-452100D01*
X-1028400Y-452000D01*
X-1028900Y-455400D01*
X-1027200Y-456600D01*
X-1025900Y-456800D01*
X-1026200Y-458200D01*
X-1030000Y-458400D01*
X-1031800Y-468900D01*
X-1030400Y-471700D01*
X-1029400D01*
X-1029600Y-473300D01*
X-1033100Y-473400D01*
X-1036100Y-472800D01*
X-1036200Y-470500D01*
X-1035900Y-467100D01*
X-1034400Y-461400D01*
X-1033800Y-458800D01*
X-1033500Y-458400D01*
X-1035000Y-458200D01*
X-1039600D01*
X-1040800Y-458300D01*
X-1043600Y-473200D01*
X-1048000Y-473000D01*
X-1045100Y-459400D01*
X-1044900Y-458400D01*
X-1048700D01*
X-1048100Y-456600D01*
X-1044900Y-456400D01*
X-1045200Y-457700D01*
X-1047600Y-457500D01*
X-1026500D01*
G01X-1049580Y-459100D02*
X-1048740Y-455700D01*
X-1044900D01*
Y-454780D01*
X-1044720Y-454060D01*
X-1044340Y-452920D01*
X-1043940Y-452120D01*
X-1043740Y-451520D01*
X-1043600Y-451260D01*
X-1042340Y-450000D01*
X-1042080Y-449860D01*
X-1040580Y-449480D01*
X-1039440Y-449300D01*
X-1036140D01*
X-1035440Y-449400D01*
X-1035480Y-449540D01*
X-1035680Y-450360D01*
X-1035880Y-451280D01*
X-1036000Y-451900D01*
X-1036740D01*
X-1037060Y-452200D01*
X-1037860Y-452600D01*
X-1038220Y-452980D01*
X-1038480Y-453740D01*
X-1038960Y-455700D01*
X-1034020D01*
X-1033720Y-455080D01*
X-1033500Y-453400D01*
X-1032940Y-451100D01*
X-1027260D01*
X-1027280Y-451180D01*
X-1027480Y-452780D01*
X-1027860Y-454280D01*
X-1028100Y-454760D01*
Y-455700D01*
X-1024800D01*
X-1024880Y-455940D01*
X-1025080Y-456940D01*
X-1025280Y-457540D01*
X-1025480Y-458560D01*
X-1025620Y-459100D01*
X-1029100D01*
Y-460000D01*
X-1029280Y-460540D01*
X-1029480Y-461540D01*
X-1029680Y-462140D01*
X-1029880Y-462960D01*
X-1030100Y-464000D01*
X-1030280Y-465560D01*
X-1030480Y-466140D01*
X-1030680Y-467140D01*
X-1030880Y-467740D01*
X-1031040Y-468400D01*
X-1031300Y-468660D01*
Y-469800D01*
X-1030300Y-470560D01*
X-1029940Y-470900D01*
X-1028220D01*
X-1028680Y-472780D01*
X-1028880Y-474120D01*
Y-474140D01*
X-1030720Y-474300D01*
X-1032860D01*
X-1034380Y-474120D01*
X-1035860Y-473740D01*
X-1036640Y-473280D01*
X-1036960Y-472660D01*
X-1037100Y-472280D01*
Y-470160D01*
X-1036920Y-469260D01*
X-1036700Y-468640D01*
X-1036500Y-466840D01*
X-1036320Y-466260D01*
X-1036120Y-465260D01*
X-1035920Y-464660D01*
X-1035720Y-463660D01*
X-1035520Y-463060D01*
X-1035320Y-462060D01*
X-1035120Y-461440D01*
X-1034820Y-459100D01*
X-1039900D01*
Y-460220D01*
X-1040280Y-461780D01*
X-1040480Y-463380D01*
X-1041280Y-466540D01*
X-1041480Y-467140D01*
X-1041700Y-468200D01*
X-1041880Y-469760D01*
X-1042080Y-470340D01*
X-1042280Y-471360D01*
X-1042480Y-472140D01*
X-1042680Y-472740D01*
X-1042880Y-473740D01*
X-1042940Y-473900D01*
X-1049140D01*
X-1048300Y-470620D01*
X-1048100Y-469020D01*
X-1047920Y-468260D01*
X-1047720Y-467660D01*
X-1047520Y-466660D01*
X-1047320Y-466060D01*
X-1047120Y-465060D01*
X-1046920Y-464460D01*
X-1046700Y-463400D01*
X-1046500Y-462020D01*
X-1046140Y-460500D01*
X-1045900Y-460040D01*
Y-459100D01*
X-1049580D01*
G01X-1038400Y-451100D02*
X-1040600Y-455800D01*
X-1043300D01*
X-1041400Y-451300D01*
X-1038900Y-451000D01*
X-1041200Y-455000D01*
X-1042000Y-455100D01*
X-1040500Y-452000D01*
G01X-1037500Y-449800D02*
X-1037800Y-451000D01*
X-1038500Y-450100D01*
X-1042000Y-450700D01*
X-1043100Y-452300D01*
X-1044100Y-455100D01*
X-1044200Y-456600D01*
X-1036600Y-456800D01*
G01X-1031100Y-472500D02*
X-1031400Y-470900D01*
X-1031900Y-472200D01*
X-1035200D01*
Y-467600D01*
X-1032000Y-453700D01*
X-1030500Y-453800D01*
X-1030000Y-456700D01*
X-1033400Y-471900D01*
X-1034300Y-471600D01*
X-1034200Y-467100D01*
X-1031400Y-454500D01*
X-1030700Y-456500D01*
X-1033700Y-470600D01*
X-1032700Y-461100D01*
G01X-1032000Y-452900D02*
X-1029300D01*
X-1028000Y-457000D01*
X-1029500Y-453600D01*
X-1029100Y-457300D01*
X-1032800Y-472800D01*
X-1030200Y-472600D01*
G54D16*
X-1600709Y4685D03*
X-1560709D03*
X-1520709D03*
X-1480709D03*
G54D25*
X-1278150Y-142362D03*
X-1212008D03*
X-408071D03*
X-341929D03*
G54D35*
G01X-1181990Y-545833D02*
X-1181410Y-545208D01*
X-1180975Y-544167D01*
X-1180685Y-542708D01*
X-1180975Y-541458D01*
X-1181555Y-540625D01*
X-1182570Y-540000D01*
X-1186485D01*
Y-552500D01*
X-1181700D01*
X-1180685Y-551667D01*
X-1180105Y-550417D01*
X-1179815Y-548958D01*
X-1180105Y-547500D01*
X-1180975Y-546250D01*
X-1181990Y-545833D01*
X-1186485D01*
G01X-1171350Y-552500D02*
X-1172510Y-552292D01*
X-1173525Y-551459D01*
X-1174395Y-550208D01*
X-1174975Y-548750D01*
X-1175265Y-547083D01*
Y-545417D01*
X-1174975Y-543750D01*
X-1174395Y-542292D01*
X-1173525Y-541042D01*
X-1172510Y-540208D01*
X-1171350Y-540000D01*
X-1170190Y-540208D01*
X-1169175Y-541042D01*
X-1168305Y-542292D01*
X-1167725Y-543750D01*
X-1167435Y-545417D01*
Y-547083D01*
X-1167725Y-548750D01*
X-1168305Y-550208D01*
X-1169175Y-551459D01*
X-1170190Y-552292D01*
X-1171350Y-552500D01*
G01X-1159550Y-540000D02*
Y-552500D01*
G01X-1162885Y-540000D02*
X-1156215D01*
G01X-1138995Y-550834D02*
X-1137835Y-551875D01*
X-1136530Y-552500D01*
X-1135370D01*
X-1134210Y-551875D01*
X-1133340Y-550834D01*
X-1132905Y-549375D01*
X-1133195Y-547917D01*
X-1133920Y-546667D01*
X-1135225Y-545833D01*
X-1136965Y-545417D01*
X-1137980Y-544584D01*
X-1138415Y-543125D01*
X-1138125Y-541667D01*
X-1137400Y-540625D01*
X-1136385Y-540000D01*
X-1135370D01*
X-1134355Y-540417D01*
X-1133485Y-541458D01*
G01X-1125890Y-540000D02*
X-1122410D01*
G01X-1124150D02*
Y-552500D01*
G01X-1125890D02*
X-1122410D01*
G01X-1115540D02*
Y-540000D01*
X-1112640D01*
X-1111480Y-540625D01*
X-1110610Y-541458D01*
X-1109885Y-542708D01*
X-1109305Y-544167D01*
X-1109160Y-546250D01*
X-1109305Y-548333D01*
X-1109885Y-549792D01*
X-1110610Y-551042D01*
X-1111480Y-551875D01*
X-1112640Y-552500D01*
X-1115540D01*
G01X-1097650D02*
X-1103450D01*
Y-540000D01*
X-1097650D01*
G01X-1099970Y-546042D02*
X-1103450D01*
G01X-1079995Y-550834D02*
X-1078835Y-551875D01*
X-1077530Y-552500D01*
X-1076370D01*
X-1075210Y-551875D01*
X-1074340Y-550834D01*
X-1073905Y-549375D01*
X-1074195Y-547917D01*
X-1074920Y-546667D01*
X-1076225Y-545833D01*
X-1077965Y-545417D01*
X-1078980Y-544584D01*
X-1079415Y-543125D01*
X-1079125Y-541667D01*
X-1078400Y-540625D01*
X-1077385Y-540000D01*
X-1076370D01*
X-1075355Y-540417D01*
X-1074485Y-541458D01*
G01X-1065150Y-552500D02*
X-1066310Y-552292D01*
X-1067325Y-551459D01*
X-1068195Y-550208D01*
X-1068775Y-548750D01*
X-1069065Y-547083D01*
Y-545417D01*
X-1068775Y-543750D01*
X-1068195Y-542292D01*
X-1067325Y-541042D01*
X-1066310Y-540208D01*
X-1065150Y-540000D01*
X-1063990Y-540208D01*
X-1062975Y-541042D01*
X-1062105Y-542292D01*
X-1061525Y-543750D01*
X-1061235Y-545417D01*
Y-547083D01*
X-1061525Y-548750D01*
X-1062105Y-550208D01*
X-1062975Y-551459D01*
X-1063990Y-552292D01*
X-1065150Y-552500D01*
G01X-1056250Y-540000D02*
Y-552500D01*
X-1050450D01*
G01X-1044740D02*
Y-540000D01*
X-1041840D01*
X-1040680Y-540625D01*
X-1039810Y-541458D01*
X-1039085Y-542708D01*
X-1038505Y-544167D01*
X-1038360Y-546250D01*
X-1038505Y-548333D01*
X-1039085Y-549792D01*
X-1039810Y-551042D01*
X-1040680Y-551875D01*
X-1041840Y-552500D01*
X-1044740D01*
G01X-1026850D02*
X-1032650D01*
Y-540000D01*
X-1026850D01*
G01X-1029170Y-546042D02*
X-1032650D01*
G01X-1020850Y-552500D02*
Y-540000D01*
X-1017225D01*
X-1016065Y-540625D01*
X-1015340Y-541458D01*
X-1015050Y-543125D01*
X-1015340Y-544792D01*
X-1016210Y-545833D01*
X-1017225Y-546458D01*
X-1020850D01*
G01X-1017225D02*
X-1015050Y-552500D01*
G01X-1009920D02*
Y-540000D01*
X-1006150Y-550417D01*
X-1002380Y-540000D01*
Y-552500D01*
G01X-997975D02*
X-994350Y-540000D01*
X-990725Y-552500D01*
G01X-992030Y-548125D02*
X-996670D01*
G01X-985595Y-550834D02*
X-984435Y-551875D01*
X-983130Y-552500D01*
X-981970D01*
X-980810Y-551875D01*
X-979940Y-550834D01*
X-979505Y-549375D01*
X-979795Y-547917D01*
X-980520Y-546667D01*
X-981825Y-545833D01*
X-983565Y-545417D01*
X-984580Y-544584D01*
X-985015Y-543125D01*
X-984725Y-541667D01*
X-984000Y-540625D01*
X-982985Y-540000D01*
X-981970D01*
X-980955Y-540417D01*
X-980085Y-541458D01*
G01X-973940Y-552500D02*
Y-540000D01*
G01X-968430D02*
X-973940Y-547709D01*
G01X-967560Y-552500D02*
X-971475Y-544167D01*
G54D26*
X-1141240Y-132520D03*
Y-112835D03*
Y-94331D03*
X-1132087Y-150630D03*
X-1113189D03*
X-1094291D03*
X-1085138Y-132520D03*
Y-112835D03*
Y-94331D03*
X-271161Y-132520D03*
Y-112835D03*
Y-94331D03*
X-262008Y-150630D03*
X-243110D03*
X-224213D03*
X-215059Y-132520D03*
Y-112835D03*
Y-94331D03*
G54D17*
X-1545118Y-178189D03*
X-675039D03*
G54D36*
G01X-1185925Y-592500D02*
X-1178575Y-577500D01*
G01X-1185925D02*
X-1178575Y-592500D01*
G01X-1168050D02*
X-1166825Y-592250D01*
X-1165425Y-591500D01*
X-1164550Y-590250D01*
X-1164200Y-588500D01*
X-1164550Y-586750D01*
X-1165600Y-585250D01*
X-1167175Y-584500D01*
X-1168925D01*
X-1169975Y-584000D01*
X-1170850Y-582750D01*
X-1171200Y-581000D01*
X-1170675Y-579250D01*
X-1169450Y-578000D01*
X-1168050Y-577500D01*
X-1166650Y-578000D01*
X-1165425Y-579250D01*
X-1164900Y-581000D01*
X-1165250Y-582750D01*
X-1166125Y-584000D01*
X-1167175Y-584500D01*
X-1168925D01*
X-1170500Y-585250D01*
X-1171550Y-586750D01*
X-1171900Y-588500D01*
X-1171550Y-590250D01*
X-1170675Y-591500D01*
X-1169275Y-592250D01*
X-1168050Y-592500D01*
G01X-1153850D02*
X-1152625Y-592250D01*
X-1151225Y-591500D01*
X-1150350Y-590250D01*
X-1150000Y-588500D01*
X-1150350Y-586750D01*
X-1151400Y-585250D01*
X-1152975Y-584500D01*
X-1154725D01*
X-1155775Y-584000D01*
X-1156650Y-582750D01*
X-1157000Y-581000D01*
X-1156475Y-579250D01*
X-1155250Y-578000D01*
X-1153850Y-577500D01*
X-1152450Y-578000D01*
X-1151225Y-579250D01*
X-1150700Y-581000D01*
X-1151050Y-582750D01*
X-1151925Y-584000D01*
X-1152975Y-584500D01*
X-1154725D01*
X-1156300Y-585250D01*
X-1157350Y-586750D01*
X-1157700Y-588500D01*
X-1157350Y-590250D01*
X-1156475Y-591500D01*
X-1155075Y-592250D01*
X-1153850Y-592500D01*
G01X-1140000D02*
X-1139650Y-589250D01*
X-1139125Y-586500D01*
X-1138425Y-584000D01*
X-1137550Y-581250D01*
X-1136150Y-577500D01*
X-1143150D01*
G01X-1129300Y-590250D02*
X-1128250Y-591500D01*
X-1127025Y-592250D01*
X-1125450Y-592500D01*
X-1123875Y-592000D01*
X-1122650Y-591000D01*
X-1121775Y-589250D01*
X-1121600Y-587250D01*
X-1121950Y-585250D01*
X-1122825Y-584000D01*
X-1124050Y-583000D01*
X-1125275Y-582750D01*
X-1126500Y-583000D01*
X-1128075Y-584000D01*
X-1127550Y-577500D01*
X-1122825D01*
G01X-1111600Y-592500D02*
X-1111250Y-589250D01*
X-1110725Y-586500D01*
X-1110025Y-584000D01*
X-1109150Y-581250D01*
X-1107750Y-577500D01*
X-1114750D01*
G01X-1097050Y-592500D02*
Y-577500D01*
X-1099150Y-580500D01*
G01Y-592500D02*
X-1094950D01*
G01X-1085125Y-587500D02*
X-1080575D01*
G01X-1068650Y-577500D02*
X-1070050Y-578000D01*
X-1071100Y-579250D01*
X-1071800Y-580750D01*
X-1072325Y-582750D01*
X-1072500Y-585000D01*
X-1072325Y-587250D01*
X-1071800Y-589250D01*
X-1071100Y-590750D01*
X-1070050Y-592000D01*
X-1068650Y-592500D01*
X-1067250Y-592000D01*
X-1066200Y-590750D01*
X-1065500Y-589250D01*
X-1064975Y-587250D01*
X-1064800Y-585000D01*
X-1064975Y-582750D01*
X-1065500Y-580750D01*
X-1066200Y-579250D01*
X-1067250Y-578000D01*
X-1068650Y-577500D01*
G01X-1054450D02*
X-1055850Y-578000D01*
X-1056900Y-579250D01*
X-1057600Y-580750D01*
X-1058125Y-582750D01*
X-1058300Y-585000D01*
X-1058125Y-587250D01*
X-1057600Y-589250D01*
X-1056900Y-590750D01*
X-1055850Y-592000D01*
X-1054450Y-592500D01*
X-1053050Y-592000D01*
X-1052000Y-590750D01*
X-1051300Y-589250D01*
X-1050775Y-587250D01*
X-1050600Y-585000D01*
X-1050775Y-582750D01*
X-1051300Y-580750D01*
X-1052000Y-579250D01*
X-1053050Y-578000D01*
X-1054450Y-577500D01*
G01X-1044100Y-590250D02*
X-1043050Y-591500D01*
X-1041825Y-592250D01*
X-1040250Y-592500D01*
X-1038675Y-592000D01*
X-1037450Y-591000D01*
X-1036575Y-589250D01*
X-1036400Y-587250D01*
X-1036750Y-585250D01*
X-1037625Y-584000D01*
X-1038850Y-583000D01*
X-1040075Y-582750D01*
X-1041300Y-583000D01*
X-1042875Y-584000D01*
X-1042350Y-577500D01*
X-1037625D01*
G01X-911875Y-592500D02*
X-907500Y-577500D01*
X-903125Y-592500D01*
G01X-904700Y-587250D02*
X-910300D01*
G54D27*
X-1141240Y-142362D03*
Y-102992D03*
Y-63622D03*
Y-24252D03*
X-1128760Y-83307D03*
X-1118917Y-4567D03*
X-1107500Y-83307D03*
X-1085138Y-122677D03*
Y-83307D03*
Y-43937D03*
Y-4567D03*
X-785200Y-83100D03*
X-271161Y-142362D03*
Y-102992D03*
Y-63622D03*
Y-24252D03*
X-258681Y-83307D03*
X-237421D03*
X-248839Y-4567D03*
X-215059Y-122677D03*
Y-83307D03*
Y-43937D03*
Y-4567D03*
G54D18*
X-1488693Y-178940D03*
X-1476693Y-64840D03*
X-618614Y-178940D03*
X-606614Y-64840D03*
G54D37*
G01X-1200000Y-560000D02*
X-890000D01*
G01Y-520000D02*
X-1200000D01*
G01X-575000Y-480000D02*
X-1200000D01*
G01X-927500Y-560000D02*
Y-600000D01*
G01X-915000Y-440000D02*
Y-480000D01*
G01X-890000D02*
Y-600000D01*
G01X-870000Y-440000D02*
Y-480000D01*
G01X-680000D02*
Y-440000D01*
G01X-1200000Y-600000D02*
X-575000D01*
Y-440000D01*
X-1200000D01*
Y-600000D01*
G54D19*
X-1410000Y0D03*
X0Y-136453D03*
X0Y0D03*
G54D28*
X-1132087Y-126220D03*
X-1094291D03*
X-262008D03*
X-224213D03*
G54D38*
G01X-1007500Y-470000D02*
X-1006450Y-475000D01*
X-1005250Y-470000D01*
X-1004050Y-475000D01*
X-1003000Y-470000D01*
G01X-1001125Y-475000D02*
X-999250Y-470000D01*
X-997375Y-475000D01*
G01X-998050Y-473250D02*
X-1000450D01*
G01X-994825Y-474333D02*
X-994225Y-474750D01*
X-993550Y-475000D01*
X-992950D01*
X-992350Y-474750D01*
X-991900Y-474333D01*
X-991675Y-473750D01*
X-991825Y-473167D01*
X-992200Y-472667D01*
X-992875Y-472333D01*
X-993775Y-472167D01*
X-994300Y-471833D01*
X-994525Y-471250D01*
X-994375Y-470667D01*
X-994000Y-470250D01*
X-993475Y-470000D01*
X-992950D01*
X-992425Y-470167D01*
X-991975Y-470583D01*
G01X-988825Y-475000D02*
Y-470000D01*
G01X-985675D02*
Y-475000D01*
G01Y-472500D02*
X-988825D01*
G01X-976525Y-474417D02*
X-976000Y-474833D01*
X-975400Y-475000D01*
X-974800Y-474833D01*
X-974275Y-474333D01*
X-973900Y-473583D01*
X-973750Y-472833D01*
Y-471917D01*
X-973900Y-471167D01*
X-974275Y-470500D01*
X-974725Y-470167D01*
X-975250Y-470000D01*
X-975850Y-470167D01*
X-976300Y-470500D01*
X-976600Y-471000D01*
X-976750Y-471667D01*
X-976600Y-472250D01*
X-976225Y-472833D01*
X-975775Y-473167D01*
X-975250Y-473250D01*
X-974650Y-473083D01*
X-974200Y-472667D01*
X-973750Y-471917D01*
G01X-969250Y-475000D02*
X-968725Y-474917D01*
X-968125Y-474667D01*
X-967750Y-474250D01*
X-967600Y-473667D01*
X-967750Y-473083D01*
X-968200Y-472583D01*
X-968875Y-472333D01*
X-969625D01*
X-970075Y-472167D01*
X-970450Y-471750D01*
X-970600Y-471167D01*
X-970375Y-470583D01*
X-969850Y-470167D01*
X-969250Y-470000D01*
X-968650Y-470167D01*
X-968125Y-470583D01*
X-967900Y-471167D01*
X-968050Y-471750D01*
X-968425Y-472167D01*
X-968875Y-472333D01*
X-969625D01*
X-970300Y-472583D01*
X-970750Y-473083D01*
X-970900Y-473667D01*
X-970750Y-474250D01*
X-970375Y-474667D01*
X-969775Y-474917D01*
X-969250Y-475000D01*
G01X-963250Y-470000D02*
X-963850Y-470167D01*
X-964300Y-470583D01*
X-964600Y-471083D01*
X-964825Y-471750D01*
X-964900Y-472500D01*
X-964825Y-473250D01*
X-964600Y-473917D01*
X-964300Y-474417D01*
X-963850Y-474833D01*
X-963250Y-475000D01*
X-962650Y-474833D01*
X-962200Y-474417D01*
X-961900Y-473917D01*
X-961675Y-473250D01*
X-961600Y-472500D01*
X-961675Y-471750D01*
X-961900Y-471083D01*
X-962200Y-470583D01*
X-962650Y-470167D01*
X-963250Y-470000D01*
G01X-958900Y-474250D02*
X-958450Y-474667D01*
X-957925Y-474917D01*
X-957250Y-475000D01*
X-956575Y-474833D01*
X-956050Y-474500D01*
X-955675Y-473917D01*
X-955600Y-473250D01*
X-955750Y-472583D01*
X-956125Y-472167D01*
X-956650Y-471833D01*
X-957175Y-471750D01*
X-957700Y-471833D01*
X-958375Y-472167D01*
X-958150Y-470000D01*
X-956125D01*
G01X-952675Y-470833D02*
X-952225Y-470333D01*
X-951700Y-470083D01*
X-951100Y-470000D01*
X-950350Y-470167D01*
X-949825Y-470583D01*
X-949675Y-471083D01*
X-949750Y-471583D01*
X-950050Y-472000D01*
X-951550Y-472833D01*
X-952225Y-473417D01*
X-952675Y-474250D01*
X-952825Y-475000D01*
X-949675D01*
G01X-946225Y-473333D02*
X-944275D01*
G01X-940675Y-472917D02*
X-940150Y-472333D01*
X-939700Y-472000D01*
X-939100Y-471833D01*
X-938575Y-472000D01*
X-938200Y-472333D01*
X-937900Y-472833D01*
X-937825Y-473417D01*
X-937900Y-473917D01*
X-938200Y-474417D01*
X-938650Y-474833D01*
X-939175Y-475000D01*
X-939775Y-474833D01*
X-940300Y-474333D01*
X-940600Y-473583D01*
X-940675Y-472750D01*
X-940525Y-471667D01*
X-940300Y-471083D01*
X-939925Y-470500D01*
X-939400Y-470083D01*
X-938875Y-470000D01*
X-938350Y-470167D01*
X-937975Y-470583D01*
G01X-934900Y-474000D02*
X-934450Y-474583D01*
X-933850Y-474917D01*
X-933175Y-475000D01*
X-932575Y-474917D01*
X-931975Y-474500D01*
X-931600Y-474000D01*
X-931525Y-473500D01*
X-931675Y-472917D01*
X-932200Y-472500D01*
X-932725Y-472333D01*
X-933400D01*
G01X-932725D02*
X-932275Y-472083D01*
X-931900Y-471667D01*
X-931750Y-471167D01*
X-931900Y-470667D01*
X-932275Y-470250D01*
X-932950Y-470000D01*
X-933625Y-470083D01*
X-934300Y-470417D01*
G01X-928525Y-474417D02*
X-928000Y-474833D01*
X-927400Y-475000D01*
X-926800Y-474833D01*
X-926275Y-474333D01*
X-925900Y-473583D01*
X-925750Y-472833D01*
Y-471917D01*
X-925900Y-471167D01*
X-926275Y-470500D01*
X-926725Y-470167D01*
X-927250Y-470000D01*
X-927850Y-470167D01*
X-928300Y-470500D01*
X-928600Y-471000D01*
X-928750Y-471667D01*
X-928600Y-472250D01*
X-928225Y-472833D01*
X-927775Y-473167D01*
X-927250Y-473250D01*
X-926650Y-473083D01*
X-926200Y-472667D01*
X-925750Y-471917D01*
G01X-922525Y-474417D02*
X-922000Y-474833D01*
X-921400Y-475000D01*
X-920800Y-474833D01*
X-920275Y-474333D01*
X-919900Y-473583D01*
X-919750Y-472833D01*
Y-471917D01*
X-919900Y-471167D01*
X-920275Y-470500D01*
X-920725Y-470167D01*
X-921250Y-470000D01*
X-921850Y-470167D01*
X-922300Y-470500D01*
X-922600Y-471000D01*
X-922750Y-471667D01*
X-922600Y-472250D01*
X-922225Y-472833D01*
X-921775Y-473167D01*
X-921250Y-473250D01*
X-920650Y-473083D01*
X-920200Y-472667D01*
X-919750Y-471917D01*
G01X-1006750Y-465000D02*
Y-460000D01*
X-1004875D01*
X-1004275Y-460250D01*
X-1003900Y-460583D01*
X-1003750Y-461250D01*
X-1003900Y-461917D01*
X-1004350Y-462333D01*
X-1004875Y-462583D01*
X-1006750D01*
G01X-1004875D02*
X-1003750Y-465000D01*
G01X-997750D02*
X-1000750D01*
Y-460000D01*
X-997750D01*
G01X-998950Y-462417D02*
X-1000750D01*
G01X-994900Y-465000D02*
Y-460000D01*
X-993400D01*
X-992800Y-460250D01*
X-992350Y-460583D01*
X-991975Y-461083D01*
X-991675Y-461667D01*
X-991600Y-462500D01*
X-991675Y-463333D01*
X-991975Y-463917D01*
X-992350Y-464417D01*
X-992800Y-464750D01*
X-993400Y-465000D01*
X-994900D01*
G01X-989200D02*
Y-460000D01*
X-987250Y-464167D01*
X-985300Y-460000D01*
Y-465000D01*
G01X-981250D02*
X-981850Y-464917D01*
X-982375Y-464583D01*
X-982825Y-464083D01*
X-983125Y-463500D01*
X-983275Y-462833D01*
Y-462167D01*
X-983125Y-461500D01*
X-982825Y-460917D01*
X-982375Y-460417D01*
X-981850Y-460083D01*
X-981250Y-460000D01*
X-980650Y-460083D01*
X-980125Y-460417D01*
X-979675Y-460917D01*
X-979375Y-461500D01*
X-979225Y-462167D01*
Y-462833D01*
X-979375Y-463500D01*
X-979675Y-464083D01*
X-980125Y-464583D01*
X-980650Y-464917D01*
X-981250Y-465000D01*
G01X-976975D02*
Y-460000D01*
X-973525Y-465000D01*
Y-460000D01*
G01X-970900Y-465000D02*
Y-460000D01*
X-969400D01*
X-968800Y-460250D01*
X-968350Y-460583D01*
X-967975Y-461083D01*
X-967675Y-461667D01*
X-967600Y-462500D01*
X-967675Y-463333D01*
X-967975Y-463917D01*
X-968350Y-464417D01*
X-968800Y-464750D01*
X-969400Y-465000D01*
X-970900D01*
G01X-1005250Y-455000D02*
Y-450000D01*
X-1006150Y-451000D01*
G01Y-455000D02*
X-1004350D01*
G01X-995200D02*
Y-450000D01*
X-993250Y-454167D01*
X-991300Y-450000D01*
Y-455000D01*
G01X-988150Y-450000D02*
X-986350D01*
G01X-987250D02*
Y-455000D01*
G01X-988150D02*
X-986350D01*
G01X-979600Y-450417D02*
X-980050Y-450167D01*
X-980575Y-450000D01*
X-981175D01*
X-981850Y-450250D01*
X-982375Y-450667D01*
X-982750Y-451167D01*
X-983050Y-452000D01*
X-983125Y-452750D01*
X-982975Y-453500D01*
X-982750Y-454000D01*
X-982300Y-454500D01*
X-981775Y-454833D01*
X-981250Y-455000D01*
X-980725D01*
X-980200Y-454833D01*
X-979750Y-454583D01*
X-979375Y-454250D01*
G01X-976750Y-455000D02*
Y-450000D01*
X-974875D01*
X-974275Y-450250D01*
X-973900Y-450583D01*
X-973750Y-451250D01*
X-973900Y-451917D01*
X-974350Y-452333D01*
X-974875Y-452583D01*
X-976750D01*
G01X-974875D02*
X-973750Y-455000D01*
G01X-969250D02*
X-969850Y-454917D01*
X-970375Y-454583D01*
X-970825Y-454083D01*
X-971125Y-453500D01*
X-971275Y-452833D01*
Y-452167D01*
X-971125Y-451500D01*
X-970825Y-450917D01*
X-970375Y-450417D01*
X-969850Y-450083D01*
X-969250Y-450000D01*
X-968650Y-450083D01*
X-968125Y-450417D01*
X-967675Y-450917D01*
X-967375Y-451500D01*
X-967225Y-452167D01*
Y-452833D01*
X-967375Y-453500D01*
X-967675Y-454083D01*
X-968125Y-454583D01*
X-968650Y-454917D01*
X-969250Y-455000D01*
G01X-964825Y-454333D02*
X-964225Y-454750D01*
X-963550Y-455000D01*
X-962950D01*
X-962350Y-454750D01*
X-961900Y-454333D01*
X-961675Y-453750D01*
X-961825Y-453167D01*
X-962200Y-452667D01*
X-962875Y-452333D01*
X-963775Y-452167D01*
X-964300Y-451833D01*
X-964525Y-451250D01*
X-964375Y-450667D01*
X-964000Y-450250D01*
X-963475Y-450000D01*
X-962950D01*
X-962425Y-450167D01*
X-961975Y-450583D01*
G01X-957250Y-455000D02*
X-957850Y-454917D01*
X-958375Y-454583D01*
X-958825Y-454083D01*
X-959125Y-453500D01*
X-959275Y-452833D01*
Y-452167D01*
X-959125Y-451500D01*
X-958825Y-450917D01*
X-958375Y-450417D01*
X-957850Y-450083D01*
X-957250Y-450000D01*
X-956650Y-450083D01*
X-956125Y-450417D01*
X-955675Y-450917D01*
X-955375Y-451500D01*
X-955225Y-452167D01*
Y-452833D01*
X-955375Y-453500D01*
X-955675Y-454083D01*
X-956125Y-454583D01*
X-956650Y-454917D01*
X-957250Y-455000D01*
G01X-952675D02*
Y-450000D01*
X-949825D01*
G01X-950875Y-452417D02*
X-952675D01*
G01X-945250Y-450000D02*
Y-455000D01*
G01X-946975Y-450000D02*
X-943525D01*
G01X-935500D02*
X-934450Y-455000D01*
X-933250Y-450000D01*
X-932050Y-455000D01*
X-931000Y-450000D01*
G01X-929125Y-455000D02*
X-927250Y-450000D01*
X-925375Y-455000D01*
G01X-926050Y-453250D02*
X-928450D01*
G01X-921250Y-455000D02*
Y-452750D01*
X-922750Y-450000D01*
G01X-919750D02*
X-921250Y-452750D01*
G54D29*
X-1025000Y-50942D03*
Y1459D03*
X-1015157Y-105312D03*
X-997441D03*
X-981693Y-50942D03*
Y1459D03*
X-971850Y-105312D03*
X-954134D03*
X-938386Y-50942D03*
Y1459D03*
X-145079Y-105312D03*
X-154921Y-50942D03*
Y1459D03*
X-127362Y-105312D03*
X-111614Y-50942D03*
Y1459D03*
X-101772Y-105312D03*
X-84055D03*
X-68307Y-50942D03*
Y1459D03*
G54D39*
G01X-874510Y-499000D02*
Y-493000D01*
X-871290Y-499000D01*
Y-493000D01*
G01X-867200Y-499000D02*
X-867760Y-498900D01*
X-868250Y-498500D01*
X-868670Y-497900D01*
X-868950Y-497200D01*
X-869090Y-496400D01*
Y-495600D01*
X-868950Y-494800D01*
X-868670Y-494100D01*
X-868250Y-493500D01*
X-867760Y-493100D01*
X-867200Y-493000D01*
X-866640Y-493100D01*
X-866150Y-493500D01*
X-865730Y-494100D01*
X-865450Y-494800D01*
X-865310Y-495600D01*
Y-496400D01*
X-865450Y-497200D01*
X-865730Y-497900D01*
X-866150Y-498500D01*
X-866640Y-498900D01*
X-867200Y-499000D01*
G01X-861500Y-493000D02*
Y-499000D01*
G01X-863110Y-493000D02*
X-859890D01*
G01X-856640D02*
X-854960D01*
G01X-855800D02*
Y-499000D01*
G01X-856640D02*
X-854960D01*
G01X-848560Y-493500D02*
X-848980Y-493200D01*
X-849470Y-493000D01*
X-850030D01*
X-850660Y-493300D01*
X-851150Y-493800D01*
X-851500Y-494400D01*
X-851780Y-495400D01*
X-851850Y-496300D01*
X-851710Y-497200D01*
X-851500Y-497800D01*
X-851080Y-498400D01*
X-850590Y-498800D01*
X-850100Y-499000D01*
X-849610D01*
X-849120Y-498800D01*
X-848700Y-498500D01*
X-848350Y-498100D01*
G01X-843000Y-499000D02*
X-845800D01*
Y-493000D01*
X-843000D01*
G01X-844120Y-495900D02*
X-845800D01*
G01X-833000Y-499000D02*
X-833560Y-498900D01*
X-834050Y-498500D01*
X-834470Y-497900D01*
X-834750Y-497200D01*
X-834890Y-496400D01*
Y-495600D01*
X-834750Y-494800D01*
X-834470Y-494100D01*
X-834050Y-493500D01*
X-833560Y-493100D01*
X-833000Y-493000D01*
X-832440Y-493100D01*
X-831950Y-493500D01*
X-831530Y-494100D01*
X-831250Y-494800D01*
X-831110Y-495600D01*
Y-496400D01*
X-831250Y-497200D01*
X-831530Y-497900D01*
X-831950Y-498500D01*
X-832440Y-498900D01*
X-833000Y-499000D01*
G01X-828630D02*
Y-493000D01*
X-825970D01*
G01X-826950Y-495900D02*
X-828630D01*
G01X-817300Y-499000D02*
Y-493000D01*
X-815620D01*
X-815060Y-493300D01*
X-814640Y-494000D01*
X-814500Y-494800D01*
X-814640Y-495600D01*
X-814990Y-496200D01*
X-815620Y-496500D01*
X-817300D01*
G01X-811600Y-499000D02*
Y-493000D01*
X-809850D01*
X-809290Y-493300D01*
X-808940Y-493700D01*
X-808800Y-494500D01*
X-808940Y-495300D01*
X-809360Y-495800D01*
X-809850Y-496100D01*
X-811600D01*
G01X-809850D02*
X-808800Y-499000D01*
G01X-804500D02*
X-805060Y-498900D01*
X-805550Y-498500D01*
X-805970Y-497900D01*
X-806250Y-497200D01*
X-806390Y-496400D01*
Y-495600D01*
X-806250Y-494800D01*
X-805970Y-494100D01*
X-805550Y-493500D01*
X-805060Y-493100D01*
X-804500Y-493000D01*
X-803940Y-493100D01*
X-803450Y-493500D01*
X-803030Y-494100D01*
X-802750Y-494800D01*
X-802610Y-495600D01*
Y-496400D01*
X-802750Y-497200D01*
X-803030Y-497900D01*
X-803450Y-498500D01*
X-803940Y-498900D01*
X-804500Y-499000D01*
G01X-800200D02*
Y-493000D01*
X-798520D01*
X-797960Y-493300D01*
X-797540Y-494000D01*
X-797400Y-494800D01*
X-797540Y-495600D01*
X-797890Y-496200D01*
X-798520Y-496500D01*
X-800200D01*
G01X-794500Y-499000D02*
Y-493000D01*
X-792750D01*
X-792190Y-493300D01*
X-791840Y-493700D01*
X-791700Y-494500D01*
X-791840Y-495300D01*
X-792260Y-495800D01*
X-792750Y-496100D01*
X-794500D01*
G01X-792750D02*
X-791700Y-499000D01*
G01X-788240Y-493000D02*
X-786560D01*
G01X-787400D02*
Y-499000D01*
G01X-788240D02*
X-786560D01*
G01X-780300D02*
X-783100D01*
Y-493000D01*
X-780300D01*
G01X-781420Y-495900D02*
X-783100D01*
G01X-776000Y-493000D02*
Y-499000D01*
G01X-777610Y-493000D02*
X-774390D01*
G01X-772050Y-499000D02*
X-770300Y-493000D01*
X-768550Y-499000D01*
G01X-769180Y-496900D02*
X-771420D01*
G01X-766000Y-499000D02*
Y-493000D01*
X-764250D01*
X-763690Y-493300D01*
X-763340Y-493700D01*
X-763200Y-494500D01*
X-763340Y-495300D01*
X-763760Y-495800D01*
X-764250Y-496100D01*
X-766000D01*
G01X-764250D02*
X-763200Y-499000D01*
G01X-758900D02*
Y-496300D01*
X-760300Y-493000D01*
G01X-757500D02*
X-758900Y-496300D01*
G01X-748900Y-499000D02*
Y-493000D01*
X-747220D01*
X-746660Y-493300D01*
X-746240Y-494000D01*
X-746100Y-494800D01*
X-746240Y-495600D01*
X-746590Y-496200D01*
X-747220Y-496500D01*
X-748900D01*
G01X-743200Y-499000D02*
Y-493000D01*
X-741450D01*
X-740890Y-493300D01*
X-740540Y-493700D01*
X-740400Y-494500D01*
X-740540Y-495300D01*
X-740960Y-495800D01*
X-741450Y-496100D01*
X-743200D01*
G01X-741450D02*
X-740400Y-499000D01*
G01X-736100D02*
X-736660Y-498900D01*
X-737150Y-498500D01*
X-737570Y-497900D01*
X-737850Y-497200D01*
X-737990Y-496400D01*
Y-495600D01*
X-737850Y-494800D01*
X-737570Y-494100D01*
X-737150Y-493500D01*
X-736660Y-493100D01*
X-736100Y-493000D01*
X-735540Y-493100D01*
X-735050Y-493500D01*
X-734630Y-494100D01*
X-734350Y-494800D01*
X-734210Y-495600D01*
Y-496400D01*
X-734350Y-497200D01*
X-734630Y-497900D01*
X-735050Y-498500D01*
X-735540Y-498900D01*
X-736100Y-499000D01*
G01X-731800D02*
Y-493000D01*
X-730120D01*
X-729560Y-493300D01*
X-729140Y-494000D01*
X-729000Y-494800D01*
X-729140Y-495600D01*
X-729490Y-496200D01*
X-730120Y-496500D01*
X-731800D01*
G01X-723300Y-499000D02*
X-726100D01*
Y-493000D01*
X-723300D01*
G01X-724420Y-495900D02*
X-726100D01*
G01X-720400Y-499000D02*
Y-493000D01*
X-718650D01*
X-718090Y-493300D01*
X-717740Y-493700D01*
X-717600Y-494500D01*
X-717740Y-495300D01*
X-718160Y-495800D01*
X-718650Y-496100D01*
X-720400D01*
G01X-718650D02*
X-717600Y-499000D01*
G01X-713300Y-493000D02*
Y-499000D01*
G01X-714910Y-493000D02*
X-711690D01*
G01X-707600Y-499000D02*
Y-496300D01*
X-709000Y-493000D01*
G01X-706200D02*
X-707600Y-496300D01*
G01X-701900Y-499200D02*
X-702040Y-499100D01*
Y-498900D01*
X-701900Y-498800D01*
X-701760Y-498900D01*
Y-499100D01*
X-701900Y-499200D01*
G01Y-496500D02*
X-702040Y-496400D01*
Y-496200D01*
X-701900Y-496100D01*
X-701760Y-496200D01*
Y-496400D01*
X-701900Y-496500D01*
M02*
